G04 ================== begin FILE IDENTIFICATION RECORD ==================*
G04 Layout Name:  12004-1.brd*
G04 Film Name:    NOTICE*
G04 File Format:  Gerber RS274X*
G04 File Origin:  Cadence Allegro 16.2-S033*
G04 Origin Date:  Tue Oct 16 14:35:58 2012*
G04 *
G04 Layer:  MANUFACTURING/THERMAL*
G04 *
G04 Offset:    (0.00 0.00)*
G04 Mirror:    No*
G04 Mode:      Positive*
G04 Rotation:  0*
G04 FullContactRelief:  No*
G04 UndefLineWidth:     6.00*
G04 ================== end FILE IDENTIFICATION RECORD ====================*
%FSLAX35Y35*MOIN*%
%IR0*IPPOS*OFA0.00000B0.00000*MIA0B0*SFA1.00000B1.00000*%
%ADD10C,.02*%
%ADD11C,.015*%
%ADD12C,.006*%
G75*
%LPD*%
G75*
G36*
G01X-132729Y686976D02*
G02X-154275Y708522I7501J29047D01*
G01X-159415Y708523D01*
G03X-132728Y681836I34187J7500D01*
G01X-132729Y686976D01*
G37*
G36*
G01X-154275Y723523D02*
G02X-132729Y745070I29047J-7500D01*
G01X-132728Y750210D01*
G03X-159415Y723522I7500J-34187D01*
G01X-154275Y723523D01*
G37*
G36*
G01X-77858Y236904D02*
G02X-105417Y274461I11812J37557D01*
G01Y290209D01*
X-99512D01*
Y274461D01*
G03X-77858Y243150I33464J0D01*
G01Y236904D01*
G37*
G36*
G01X-105417Y329579D02*
Y345327D01*
G02X-77858Y382884I39371J0D01*
G01Y376638D01*
G03X-99512Y345327I11810J-31311D01*
G01Y329579D01*
X-105417D01*
G37*
G36*
G01X-96181Y708522D02*
G02X-117728Y686976I-29047J7501D01*
G01X-117729Y681836D01*
G03X-91041Y708523I-7499J34187D01*
G01X-96181Y708522D01*
G37*
G36*
G01X-117728Y745070D02*
G02X-96181Y723523I-7500J-29047D01*
G01X-91041Y723522D01*
G03X-117729Y750210I-34187J-7499D01*
G01X-117728Y745070D01*
G37*
G36*
G01X-54236Y236904D02*
Y243150D01*
G03X-32582Y274461I-11810J31311D01*
G01Y290209D01*
X-26677D01*
Y274461D01*
G02X-54236Y236904I-39371J0D01*
G37*
G36*
G01X-32582Y329579D02*
Y345327D01*
G03X-54236Y376638I-33464J0D01*
G01Y382884D01*
G02X-26677Y345327I-11812J-37557D01*
G01Y329579D01*
X-32582D01*
G37*
G54D10*
G01X-297747Y56394D02*
Y67019D01*
X-297330Y68060D01*
X-296497Y68686D01*
X-295247Y68894D01*
X-293997Y68477D01*
X-293372Y67436D01*
G01X-295872Y63894D02*
X-300039D01*
G01X-280997Y56394D02*
X-282247Y56602D01*
X-283497Y57435D01*
X-284331Y58894D01*
X-284747Y60561D01*
X-284331Y62227D01*
X-283497Y63686D01*
X-282247Y64519D01*
X-280997Y64727D01*
X-279747Y64519D01*
X-278497Y63686D01*
X-277664Y62227D01*
X-277455Y60561D01*
X-277664Y58894D01*
X-278497Y57435D01*
X-279747Y56602D01*
X-280997Y56394D01*
G01X-265497D02*
Y68894D01*
G01X-249997Y56394D02*
Y68894D01*
G01X-234497Y56394D02*
X-235747Y56602D01*
X-236997Y57435D01*
X-237831Y58894D01*
X-238247Y60561D01*
X-237831Y62227D01*
X-236997Y63686D01*
X-235747Y64519D01*
X-234497Y64727D01*
X-233247Y64519D01*
X-231997Y63686D01*
X-231164Y62227D01*
X-230955Y60561D01*
X-231164Y58894D01*
X-231997Y57435D01*
X-233247Y56602D01*
X-234497Y56394D01*
G01X-224206Y64727D02*
X-221705Y56394D01*
X-218997Y64727D01*
X-216289Y56394D01*
X-213788Y64727D01*
G01X-190914Y53269D02*
X-189455Y52436D01*
X-187789Y52227D01*
X-186330Y52436D01*
X-185080Y53477D01*
X-184247Y54936D01*
Y64727D01*
G01Y63061D02*
X-185080Y63894D01*
X-186330Y64519D01*
X-187789Y64727D01*
X-189455Y64311D01*
X-190497Y63477D01*
X-191331Y62019D01*
X-191747Y60561D01*
X-191539Y59310D01*
X-190705Y57852D01*
X-189455Y56811D01*
X-187789Y56394D01*
X-186539Y56602D01*
X-185080Y57435D01*
X-184247Y58269D01*
G01X-175622Y62019D02*
X-168955D01*
X-169580Y63477D01*
X-170622Y64311D01*
X-172080Y64727D01*
X-173539Y64519D01*
X-174789Y63894D01*
X-175622Y62436D01*
X-176039Y61185D01*
Y59936D01*
X-175622Y58686D01*
X-174580Y57435D01*
X-173330Y56602D01*
X-171872Y56394D01*
X-170414Y56811D01*
X-168955Y58060D01*
G01X-159914Y56394D02*
Y64727D01*
G01Y63061D02*
X-158872Y63894D01*
X-157830Y64519D01*
X-156372Y64727D01*
X-155330Y64519D01*
X-154080Y63894D01*
G01X-145247Y56394D02*
Y68894D01*
G01Y62644D02*
X-144205Y63894D01*
X-142955Y64519D01*
X-141705Y64727D01*
X-139830Y64311D01*
X-138580Y63477D01*
X-137747Y62019D01*
Y60352D01*
X-138164Y58686D01*
X-138997Y57435D01*
X-140455Y56602D01*
X-141705Y56394D01*
X-142955Y56602D01*
X-144205Y57227D01*
X-145247Y58269D01*
G01X-129122Y62019D02*
X-122455D01*
X-123080Y63477D01*
X-124122Y64311D01*
X-125580Y64727D01*
X-127039Y64519D01*
X-128289Y63894D01*
X-129122Y62436D01*
X-129539Y61185D01*
Y59936D01*
X-129122Y58686D01*
X-128080Y57435D01*
X-126830Y56602D01*
X-125372Y56394D01*
X-123914Y56811D01*
X-122455Y58060D01*
G01X-113414Y56394D02*
Y64727D01*
G01Y63061D02*
X-112372Y63894D01*
X-111330Y64519D01*
X-109872Y64727D01*
X-108830Y64519D01*
X-107580Y63894D01*
G01X-75747Y68894D02*
Y56394D01*
G01Y58269D02*
X-76580Y57227D01*
X-77830Y56602D01*
X-79289Y56394D01*
X-80955Y56811D01*
X-82205Y57852D01*
X-83039Y59102D01*
X-83247Y60561D01*
X-83039Y62019D01*
X-82205Y63269D01*
X-80955Y64311D01*
X-79289Y64727D01*
X-77830Y64519D01*
X-76789Y64102D01*
X-75747Y63269D01*
G01X-67122Y62019D02*
X-60455D01*
X-61080Y63477D01*
X-62122Y64311D01*
X-63580Y64727D01*
X-65039Y64519D01*
X-66289Y63894D01*
X-67122Y62436D01*
X-67539Y61185D01*
Y59936D01*
X-67122Y58686D01*
X-66080Y57435D01*
X-64830Y56602D01*
X-63372Y56394D01*
X-61914Y56811D01*
X-60455Y58060D01*
G01X-51622Y57852D02*
X-50580Y57019D01*
X-49122Y56394D01*
X-47872D01*
X-46622Y56811D01*
X-45789Y57435D01*
X-45372Y58269D01*
X-45580Y59519D01*
X-46414Y60144D01*
X-50164Y61394D01*
X-50997Y62852D01*
X-50580Y63894D01*
X-49747Y64519D01*
X-48497Y64727D01*
X-47247Y64519D01*
X-45997Y63894D01*
G01X-32997Y64727D02*
Y56394D01*
G01Y68060D02*
X-33414Y68269D01*
Y68686D01*
X-32997Y68894D01*
X-32580Y68686D01*
Y68269D01*
X-32997Y68060D01*
G01X-20414Y53269D02*
X-18955Y52436D01*
X-17289Y52227D01*
X-15830Y52436D01*
X-14580Y53477D01*
X-13747Y54936D01*
Y64727D01*
G01Y63061D02*
X-14580Y63894D01*
X-15830Y64519D01*
X-17289Y64727D01*
X-18955Y64311D01*
X-19997Y63477D01*
X-20831Y62019D01*
X-21247Y60561D01*
X-21039Y59310D01*
X-20205Y57852D01*
X-18955Y56811D01*
X-17289Y56394D01*
X-16039Y56602D01*
X-14580Y57435D01*
X-13747Y58269D01*
G01X-5539Y56394D02*
Y64727D01*
G01Y62644D02*
X-4705Y63686D01*
X-3455Y64519D01*
X-1789Y64727D01*
X-330Y64519D01*
X920Y63686D01*
X1545Y62227D01*
Y56394D01*
G01X-300455Y78094D02*
Y90594D01*
X-292539D01*
G01X-295455Y84552D02*
X-300455D01*
G01X-280997Y78094D02*
X-282247Y78302D01*
X-283497Y79135D01*
X-284331Y80594D01*
X-284747Y82261D01*
X-284331Y83927D01*
X-283497Y85386D01*
X-282247Y86219D01*
X-280997Y86427D01*
X-279747Y86219D01*
X-278497Y85386D01*
X-277664Y83927D01*
X-277455Y82261D01*
X-277664Y80594D01*
X-278497Y79135D01*
X-279747Y78302D01*
X-280997Y78094D01*
G01X-268414D02*
Y86427D01*
G01Y84761D02*
X-267372Y85594D01*
X-266330Y86219D01*
X-264872Y86427D01*
X-263830Y86219D01*
X-262580Y85594D01*
G01X-238455Y88511D02*
X-237205Y89760D01*
X-235747Y90386D01*
X-234080Y90594D01*
X-231997Y90177D01*
X-230539Y89136D01*
X-230122Y87886D01*
X-230330Y86635D01*
X-231164Y85594D01*
X-235330Y83511D01*
X-237205Y82052D01*
X-238455Y79969D01*
X-238872Y78094D01*
X-230122D01*
G01X-219414D02*
X-218997Y80802D01*
X-218372Y83094D01*
X-217539Y85177D01*
X-216497Y87469D01*
X-214830Y90594D01*
X-223164D01*
G01X-200997Y78094D02*
Y90594D01*
X-208706Y81636D01*
X-198288D01*
G01X-192372Y78094D02*
X-183622Y90594D01*
G01X-192372D02*
X-183622Y78094D01*
G01X-159914Y74969D02*
X-158455Y74136D01*
X-156789Y73927D01*
X-155330Y74136D01*
X-154080Y75177D01*
X-153247Y76636D01*
Y86427D01*
G01Y84761D02*
X-154080Y85594D01*
X-155330Y86219D01*
X-156789Y86427D01*
X-158455Y86011D01*
X-159497Y85177D01*
X-160331Y83719D01*
X-160747Y82261D01*
X-160539Y81010D01*
X-159705Y79552D01*
X-158455Y78511D01*
X-156789Y78094D01*
X-155539Y78302D01*
X-154080Y79135D01*
X-153247Y79969D01*
G01X-144622Y83719D02*
X-137955D01*
X-138580Y85177D01*
X-139622Y86011D01*
X-141080Y86427D01*
X-142539Y86219D01*
X-143789Y85594D01*
X-144622Y84136D01*
X-145039Y82885D01*
Y81636D01*
X-144622Y80386D01*
X-143580Y79135D01*
X-142330Y78302D01*
X-140872Y78094D01*
X-139414Y78511D01*
X-137955Y79760D01*
G01X-128914Y78094D02*
Y86427D01*
G01Y84761D02*
X-127872Y85594D01*
X-126830Y86219D01*
X-125372Y86427D01*
X-124330Y86219D01*
X-123080Y85594D01*
G01X-114247Y78094D02*
Y90594D01*
G01Y84344D02*
X-113205Y85594D01*
X-111955Y86219D01*
X-110705Y86427D01*
X-108830Y86011D01*
X-107580Y85177D01*
X-106747Y83719D01*
Y82052D01*
X-107164Y80386D01*
X-107997Y79135D01*
X-109455Y78302D01*
X-110705Y78094D01*
X-111955Y78302D01*
X-113205Y78927D01*
X-114247Y79969D01*
G01X-98122Y83719D02*
X-91455D01*
X-92080Y85177D01*
X-93122Y86011D01*
X-94580Y86427D01*
X-96039Y86219D01*
X-97289Y85594D01*
X-98122Y84136D01*
X-98539Y82885D01*
Y81636D01*
X-98122Y80386D01*
X-97080Y79135D01*
X-95830Y78302D01*
X-94372Y78094D01*
X-92914Y78511D01*
X-91455Y79760D01*
G01X-82414Y78094D02*
Y86427D01*
G01Y84761D02*
X-81372Y85594D01*
X-80330Y86219D01*
X-78872Y86427D01*
X-77830Y86219D01*
X-76580Y85594D01*
G01X-49747Y78094D02*
Y88719D01*
X-49330Y89760D01*
X-48497Y90386D01*
X-47247Y90594D01*
X-45997Y90177D01*
X-45372Y89136D01*
G01X-47872Y85594D02*
X-52039D01*
G01X-32997Y78094D02*
X-34247Y78302D01*
X-35497Y79135D01*
X-36331Y80594D01*
X-36747Y82261D01*
X-36331Y83927D01*
X-35497Y85386D01*
X-34247Y86219D01*
X-32997Y86427D01*
X-31747Y86219D01*
X-30497Y85386D01*
X-29664Y83927D01*
X-29455Y82261D01*
X-29664Y80594D01*
X-30497Y79135D01*
X-31747Y78302D01*
X-32997Y78094D01*
G01X-20414D02*
Y86427D01*
G01Y84761D02*
X-19372Y85594D01*
X-18330Y86219D01*
X-16872Y86427D01*
X-15830Y86219D01*
X-14580Y85594D01*
G01X-8247Y78094D02*
Y86427D01*
G01Y84136D02*
X-7622Y85177D01*
X-6580Y86011D01*
X-5122Y86427D01*
X-3664Y86011D01*
X-2622Y85177D01*
X-1997Y84136D01*
Y78094D01*
G01Y84136D02*
X-1372Y85177D01*
X-330Y86011D01*
X1128Y86427D01*
X2586Y86011D01*
X3628Y85177D01*
X4253Y83927D01*
Y78094D01*
G01X17253D02*
Y86427D01*
G01Y84969D02*
X16420Y85802D01*
X15170Y86219D01*
X13711Y86427D01*
X12253Y86011D01*
X11003Y85177D01*
X10169Y83927D01*
X9753Y82261D01*
X10169Y80594D01*
X11003Y79344D01*
X12253Y78511D01*
X13711Y78094D01*
X15170Y78302D01*
X16420Y78927D01*
X17253Y79760D01*
G01X29003Y90594D02*
Y78094D01*
G01X26086Y86427D02*
X31920D01*
G01X60003Y90594D02*
Y78094D01*
G01X57086Y86427D02*
X62920D01*
G01X71961Y78094D02*
Y90594D01*
G01Y84552D02*
X73003Y85594D01*
X74045Y86219D01*
X75711Y86427D01*
X76961Y86219D01*
X78420Y85386D01*
X79045Y84136D01*
Y78094D01*
G01X87878Y83719D02*
X94545D01*
X93920Y85177D01*
X92878Y86011D01*
X91420Y86427D01*
X89961Y86219D01*
X88711Y85594D01*
X87878Y84136D01*
X87461Y82885D01*
Y81636D01*
X87878Y80386D01*
X88920Y79135D01*
X90170Y78302D01*
X91628Y78094D01*
X93086Y78511D01*
X94545Y79760D01*
G01X103586Y78094D02*
Y86427D01*
G01Y84761D02*
X104628Y85594D01*
X105670Y86219D01*
X107128Y86427D01*
X108170Y86219D01*
X109420Y85594D01*
G01X115753Y78094D02*
Y86427D01*
G01Y84136D02*
X116378Y85177D01*
X117420Y86011D01*
X118878Y86427D01*
X120336Y86011D01*
X121378Y85177D01*
X122003Y84136D01*
Y78094D01*
G01Y84136D02*
X122628Y85177D01*
X123670Y86011D01*
X125128Y86427D01*
X126586Y86011D01*
X127628Y85177D01*
X128253Y83927D01*
Y78094D01*
G01X141253D02*
Y86427D01*
G01Y84969D02*
X140420Y85802D01*
X139170Y86219D01*
X137711Y86427D01*
X136253Y86011D01*
X135003Y85177D01*
X134169Y83927D01*
X133753Y82261D01*
X134169Y80594D01*
X135003Y79344D01*
X136253Y78511D01*
X137711Y78094D01*
X139170Y78302D01*
X140420Y78927D01*
X141253Y79760D01*
G01X153003Y78094D02*
Y90594D01*
G01X181086Y78094D02*
Y86427D01*
G01Y84761D02*
X182128Y85594D01*
X183170Y86219D01*
X184628Y86427D01*
X185670Y86219D01*
X186920Y85594D01*
G01X196378Y83719D02*
X203045D01*
X202420Y85177D01*
X201378Y86011D01*
X199920Y86427D01*
X198461Y86219D01*
X197211Y85594D01*
X196378Y84136D01*
X195961Y82885D01*
Y81636D01*
X196378Y80386D01*
X197420Y79135D01*
X198670Y78302D01*
X200128Y78094D01*
X201586Y78511D01*
X203045Y79760D01*
G01X215003Y78094D02*
Y90594D01*
G01X230503Y86427D02*
Y78094D01*
G01Y89760D02*
X230086Y89969D01*
Y90386D01*
X230503Y90594D01*
X230920Y90386D01*
Y89969D01*
X230503Y89760D01*
G01X242878Y83719D02*
X249545D01*
X248920Y85177D01*
X247878Y86011D01*
X246420Y86427D01*
X244961Y86219D01*
X243711Y85594D01*
X242878Y84136D01*
X242461Y82885D01*
Y81636D01*
X242878Y80386D01*
X243920Y79135D01*
X245170Y78302D01*
X246628Y78094D01*
X248086Y78511D01*
X249545Y79760D01*
G01X260253Y78094D02*
Y88719D01*
X260670Y89760D01*
X261503Y90386D01*
X262753Y90594D01*
X264003Y90177D01*
X264628Y89136D01*
G01X262128Y85594D02*
X257961D01*
G01X-290855Y531994D02*
Y544494D01*
X-282939D01*
G01X-285855Y538452D02*
X-290855D01*
G01X-271397Y531994D02*
X-272647Y532202D01*
X-273897Y533035D01*
X-274731Y534494D01*
X-275147Y536161D01*
X-274731Y537827D01*
X-273897Y539286D01*
X-272647Y540119D01*
X-271397Y540327D01*
X-270147Y540119D01*
X-268897Y539286D01*
X-268064Y537827D01*
X-267855Y536161D01*
X-268064Y534494D01*
X-268897Y533035D01*
X-270147Y532202D01*
X-271397Y531994D01*
G01X-258814D02*
Y540327D01*
G01Y538661D02*
X-257772Y539494D01*
X-256730Y540119D01*
X-255272Y540327D01*
X-254230Y540119D01*
X-252980Y539494D01*
G01X-228855Y542411D02*
X-227605Y543660D01*
X-226147Y544286D01*
X-224480Y544494D01*
X-222397Y544077D01*
X-220939Y543036D01*
X-220522Y541786D01*
X-220730Y540535D01*
X-221564Y539494D01*
X-225730Y537411D01*
X-227605Y535952D01*
X-228855Y533869D01*
X-229272Y531994D01*
X-220522D01*
G01X-209814D02*
X-209397Y534702D01*
X-208772Y536994D01*
X-207939Y539077D01*
X-206897Y541369D01*
X-205230Y544494D01*
X-213564D01*
G01X-191397Y531994D02*
Y544494D01*
X-199106Y535536D01*
X-188688D01*
G01X-182772Y531994D02*
X-174022Y544494D01*
G01X-182772D02*
X-174022Y531994D01*
G01X-150314Y528869D02*
X-148855Y528036D01*
X-147189Y527827D01*
X-145730Y528036D01*
X-144480Y529077D01*
X-143647Y530536D01*
Y540327D01*
G01Y538661D02*
X-144480Y539494D01*
X-145730Y540119D01*
X-147189Y540327D01*
X-148855Y539911D01*
X-149897Y539077D01*
X-150731Y537619D01*
X-151147Y536161D01*
X-150939Y534910D01*
X-150105Y533452D01*
X-148855Y532411D01*
X-147189Y531994D01*
X-145939Y532202D01*
X-144480Y533035D01*
X-143647Y533869D01*
G01X-135022Y537619D02*
X-128355D01*
X-128980Y539077D01*
X-130022Y539911D01*
X-131480Y540327D01*
X-132939Y540119D01*
X-134189Y539494D01*
X-135022Y538036D01*
X-135439Y536785D01*
Y535536D01*
X-135022Y534286D01*
X-133980Y533035D01*
X-132730Y532202D01*
X-131272Y531994D01*
X-129814Y532411D01*
X-128355Y533660D01*
G01X-119314Y531994D02*
Y540327D01*
G01Y538661D02*
X-118272Y539494D01*
X-117230Y540119D01*
X-115772Y540327D01*
X-114730Y540119D01*
X-113480Y539494D01*
G01X-104647Y531994D02*
Y544494D01*
G01Y538244D02*
X-103605Y539494D01*
X-102355Y540119D01*
X-101105Y540327D01*
X-99230Y539911D01*
X-97980Y539077D01*
X-97147Y537619D01*
Y535952D01*
X-97564Y534286D01*
X-98397Y533035D01*
X-99855Y532202D01*
X-101105Y531994D01*
X-102355Y532202D01*
X-103605Y532827D01*
X-104647Y533869D01*
G01X-88522Y537619D02*
X-81855D01*
X-82480Y539077D01*
X-83522Y539911D01*
X-84980Y540327D01*
X-86439Y540119D01*
X-87689Y539494D01*
X-88522Y538036D01*
X-88939Y536785D01*
Y535536D01*
X-88522Y534286D01*
X-87480Y533035D01*
X-86230Y532202D01*
X-84772Y531994D01*
X-83314Y532411D01*
X-81855Y533660D01*
G01X-72814Y531994D02*
Y540327D01*
G01Y538661D02*
X-71772Y539494D01*
X-70730Y540119D01*
X-69272Y540327D01*
X-68230Y540119D01*
X-66980Y539494D01*
G01X-40147Y531994D02*
Y542619D01*
X-39730Y543660D01*
X-38897Y544286D01*
X-37647Y544494D01*
X-36397Y544077D01*
X-35772Y543036D01*
G01X-38272Y539494D02*
X-42439D01*
G01X-23397Y531994D02*
X-24647Y532202D01*
X-25897Y533035D01*
X-26731Y534494D01*
X-27147Y536161D01*
X-26731Y537827D01*
X-25897Y539286D01*
X-24647Y540119D01*
X-23397Y540327D01*
X-22147Y540119D01*
X-20897Y539286D01*
X-20064Y537827D01*
X-19855Y536161D01*
X-20064Y534494D01*
X-20897Y533035D01*
X-22147Y532202D01*
X-23397Y531994D01*
G01X-10814D02*
Y540327D01*
G01Y538661D02*
X-9772Y539494D01*
X-8730Y540119D01*
X-7272Y540327D01*
X-6230Y540119D01*
X-4980Y539494D01*
G01X1353Y531994D02*
Y540327D01*
G01Y538036D02*
X1978Y539077D01*
X3020Y539911D01*
X4478Y540327D01*
X5936Y539911D01*
X6978Y539077D01*
X7603Y538036D01*
Y531994D01*
G01Y538036D02*
X8228Y539077D01*
X9270Y539911D01*
X10728Y540327D01*
X12186Y539911D01*
X13228Y539077D01*
X13853Y537827D01*
Y531994D01*
G01X26853D02*
Y540327D01*
G01Y538869D02*
X26020Y539702D01*
X24770Y540119D01*
X23311Y540327D01*
X21853Y539911D01*
X20603Y539077D01*
X19769Y537827D01*
X19353Y536161D01*
X19769Y534494D01*
X20603Y533244D01*
X21853Y532411D01*
X23311Y531994D01*
X24770Y532202D01*
X26020Y532827D01*
X26853Y533660D01*
G01X38603Y544494D02*
Y531994D01*
G01X35686Y540327D02*
X41520D01*
G01X69603Y544494D02*
Y531994D01*
G01X66686Y540327D02*
X72520D01*
G01X81561Y531994D02*
Y544494D01*
G01Y538452D02*
X82603Y539494D01*
X83645Y540119D01*
X85311Y540327D01*
X86561Y540119D01*
X88020Y539286D01*
X88645Y538036D01*
Y531994D01*
G01X97478Y537619D02*
X104145D01*
X103520Y539077D01*
X102478Y539911D01*
X101020Y540327D01*
X99561Y540119D01*
X98311Y539494D01*
X97478Y538036D01*
X97061Y536785D01*
Y535536D01*
X97478Y534286D01*
X98520Y533035D01*
X99770Y532202D01*
X101228Y531994D01*
X102686Y532411D01*
X104145Y533660D01*
G01X113186Y531994D02*
Y540327D01*
G01Y538661D02*
X114228Y539494D01*
X115270Y540119D01*
X116728Y540327D01*
X117770Y540119D01*
X119020Y539494D01*
G01X125353Y531994D02*
Y540327D01*
G01Y538036D02*
X125978Y539077D01*
X127020Y539911D01*
X128478Y540327D01*
X129936Y539911D01*
X130978Y539077D01*
X131603Y538036D01*
Y531994D01*
G01Y538036D02*
X132228Y539077D01*
X133270Y539911D01*
X134728Y540327D01*
X136186Y539911D01*
X137228Y539077D01*
X137853Y537827D01*
Y531994D01*
G01X150853D02*
Y540327D01*
G01Y538869D02*
X150020Y539702D01*
X148770Y540119D01*
X147311Y540327D01*
X145853Y539911D01*
X144603Y539077D01*
X143769Y537827D01*
X143353Y536161D01*
X143769Y534494D01*
X144603Y533244D01*
X145853Y532411D01*
X147311Y531994D01*
X148770Y532202D01*
X150020Y532827D01*
X150853Y533660D01*
G01X162603Y531994D02*
Y544494D01*
G01X190686Y531994D02*
Y540327D01*
G01Y538661D02*
X191728Y539494D01*
X192770Y540119D01*
X194228Y540327D01*
X195270Y540119D01*
X196520Y539494D01*
G01X205978Y537619D02*
X212645D01*
X212020Y539077D01*
X210978Y539911D01*
X209520Y540327D01*
X208061Y540119D01*
X206811Y539494D01*
X205978Y538036D01*
X205561Y536785D01*
Y535536D01*
X205978Y534286D01*
X207020Y533035D01*
X208270Y532202D01*
X209728Y531994D01*
X211186Y532411D01*
X212645Y533660D01*
G01X224603Y531994D02*
Y544494D01*
G01X240103Y540327D02*
Y531994D01*
G01Y543660D02*
X239686Y543869D01*
Y544286D01*
X240103Y544494D01*
X240520Y544286D01*
Y543869D01*
X240103Y543660D01*
G01X252478Y537619D02*
X259145D01*
X258520Y539077D01*
X257478Y539911D01*
X256020Y540327D01*
X254561Y540119D01*
X253311Y539494D01*
X252478Y538036D01*
X252061Y536785D01*
Y535536D01*
X252478Y534286D01*
X253520Y533035D01*
X254770Y532202D01*
X256228Y531994D01*
X257686Y532411D01*
X259145Y533660D01*
G01X269853Y531994D02*
Y542619D01*
X270270Y543660D01*
X271103Y544286D01*
X272353Y544494D01*
X273603Y544077D01*
X274228Y543036D01*
G01X271728Y539494D02*
X267561D01*
G01X-288147Y510294D02*
Y520919D01*
X-287730Y521960D01*
X-286897Y522586D01*
X-285647Y522794D01*
X-284397Y522377D01*
X-283772Y521336D01*
G01X-286272Y517794D02*
X-290439D01*
G01X-271397Y510294D02*
X-272647Y510502D01*
X-273897Y511335D01*
X-274731Y512794D01*
X-275147Y514461D01*
X-274731Y516127D01*
X-273897Y517586D01*
X-272647Y518419D01*
X-271397Y518627D01*
X-270147Y518419D01*
X-268897Y517586D01*
X-268064Y516127D01*
X-267855Y514461D01*
X-268064Y512794D01*
X-268897Y511335D01*
X-270147Y510502D01*
X-271397Y510294D01*
G01X-255897D02*
Y522794D01*
G01X-240397Y510294D02*
Y522794D01*
G01X-224897Y510294D02*
X-226147Y510502D01*
X-227397Y511335D01*
X-228231Y512794D01*
X-228647Y514461D01*
X-228231Y516127D01*
X-227397Y517586D01*
X-226147Y518419D01*
X-224897Y518627D01*
X-223647Y518419D01*
X-222397Y517586D01*
X-221564Y516127D01*
X-221355Y514461D01*
X-221564Y512794D01*
X-222397Y511335D01*
X-223647Y510502D01*
X-224897Y510294D01*
G01X-214606Y518627D02*
X-212105Y510294D01*
X-209397Y518627D01*
X-206689Y510294D01*
X-204188Y518627D01*
G01X-181314Y507169D02*
X-179855Y506336D01*
X-178189Y506127D01*
X-176730Y506336D01*
X-175480Y507377D01*
X-174647Y508836D01*
Y518627D01*
G01Y516961D02*
X-175480Y517794D01*
X-176730Y518419D01*
X-178189Y518627D01*
X-179855Y518211D01*
X-180897Y517377D01*
X-181731Y515919D01*
X-182147Y514461D01*
X-181939Y513210D01*
X-181105Y511752D01*
X-179855Y510711D01*
X-178189Y510294D01*
X-176939Y510502D01*
X-175480Y511335D01*
X-174647Y512169D01*
G01X-166022Y515919D02*
X-159355D01*
X-159980Y517377D01*
X-161022Y518211D01*
X-162480Y518627D01*
X-163939Y518419D01*
X-165189Y517794D01*
X-166022Y516336D01*
X-166439Y515085D01*
Y513836D01*
X-166022Y512586D01*
X-164980Y511335D01*
X-163730Y510502D01*
X-162272Y510294D01*
X-160814Y510711D01*
X-159355Y511960D01*
G01X-150314Y510294D02*
Y518627D01*
G01Y516961D02*
X-149272Y517794D01*
X-148230Y518419D01*
X-146772Y518627D01*
X-145730Y518419D01*
X-144480Y517794D01*
G01X-135647Y510294D02*
Y522794D01*
G01Y516544D02*
X-134605Y517794D01*
X-133355Y518419D01*
X-132105Y518627D01*
X-130230Y518211D01*
X-128980Y517377D01*
X-128147Y515919D01*
Y514252D01*
X-128564Y512586D01*
X-129397Y511335D01*
X-130855Y510502D01*
X-132105Y510294D01*
X-133355Y510502D01*
X-134605Y511127D01*
X-135647Y512169D01*
G01X-119522Y515919D02*
X-112855D01*
X-113480Y517377D01*
X-114522Y518211D01*
X-115980Y518627D01*
X-117439Y518419D01*
X-118689Y517794D01*
X-119522Y516336D01*
X-119939Y515085D01*
Y513836D01*
X-119522Y512586D01*
X-118480Y511335D01*
X-117230Y510502D01*
X-115772Y510294D01*
X-114314Y510711D01*
X-112855Y511960D01*
G01X-103814Y510294D02*
Y518627D01*
G01Y516961D02*
X-102772Y517794D01*
X-101730Y518419D01*
X-100272Y518627D01*
X-99230Y518419D01*
X-97980Y517794D01*
G01X-66147Y522794D02*
Y510294D01*
G01Y512169D02*
X-66980Y511127D01*
X-68230Y510502D01*
X-69689Y510294D01*
X-71355Y510711D01*
X-72605Y511752D01*
X-73439Y513002D01*
X-73647Y514461D01*
X-73439Y515919D01*
X-72605Y517169D01*
X-71355Y518211D01*
X-69689Y518627D01*
X-68230Y518419D01*
X-67189Y518002D01*
X-66147Y517169D01*
G01X-57522Y515919D02*
X-50855D01*
X-51480Y517377D01*
X-52522Y518211D01*
X-53980Y518627D01*
X-55439Y518419D01*
X-56689Y517794D01*
X-57522Y516336D01*
X-57939Y515085D01*
Y513836D01*
X-57522Y512586D01*
X-56480Y511335D01*
X-55230Y510502D01*
X-53772Y510294D01*
X-52314Y510711D01*
X-50855Y511960D01*
G01X-42022Y511752D02*
X-40980Y510919D01*
X-39522Y510294D01*
X-38272D01*
X-37022Y510711D01*
X-36189Y511335D01*
X-35772Y512169D01*
X-35980Y513419D01*
X-36814Y514044D01*
X-40564Y515294D01*
X-41397Y516752D01*
X-40980Y517794D01*
X-40147Y518419D01*
X-38897Y518627D01*
X-37647Y518419D01*
X-36397Y517794D01*
G01X-23397Y518627D02*
Y510294D01*
G01Y521960D02*
X-23814Y522169D01*
Y522586D01*
X-23397Y522794D01*
X-22980Y522586D01*
Y522169D01*
X-23397Y521960D01*
G01X-10814Y507169D02*
X-9355Y506336D01*
X-7689Y506127D01*
X-6230Y506336D01*
X-4980Y507377D01*
X-4147Y508836D01*
Y518627D01*
G01Y516961D02*
X-4980Y517794D01*
X-6230Y518419D01*
X-7689Y518627D01*
X-9355Y518211D01*
X-10397Y517377D01*
X-11231Y515919D01*
X-11647Y514461D01*
X-11439Y513210D01*
X-10605Y511752D01*
X-9355Y510711D01*
X-7689Y510294D01*
X-6439Y510502D01*
X-4980Y511335D01*
X-4147Y512169D01*
G01X4061Y510294D02*
Y518627D01*
G01Y516544D02*
X4895Y517586D01*
X6145Y518419D01*
X7811Y518627D01*
X9270Y518419D01*
X10520Y517586D01*
X11145Y516127D01*
Y510294D01*
G01X-220980Y831894D02*
Y844394D01*
X-216814D01*
X-215147Y843769D01*
X-213897Y842936D01*
X-212855Y841686D01*
X-212022Y840227D01*
X-211814Y838144D01*
X-212022Y836061D01*
X-212855Y834602D01*
X-213897Y833352D01*
X-215147Y832519D01*
X-216814Y831894D01*
X-220980D01*
G01X-204022Y837519D02*
X-197355D01*
X-197980Y838977D01*
X-199022Y839811D01*
X-200480Y840227D01*
X-201939Y840019D01*
X-203189Y839394D01*
X-204022Y837936D01*
X-204439Y836685D01*
Y835436D01*
X-204022Y834186D01*
X-202980Y832935D01*
X-201730Y832102D01*
X-200272Y831894D01*
X-198814Y832311D01*
X-197355Y833560D01*
G01X-186647Y831894D02*
Y842519D01*
X-186230Y843560D01*
X-185397Y844186D01*
X-184147Y844394D01*
X-182897Y843977D01*
X-182272Y842936D01*
G01X-184772Y839394D02*
X-188939D01*
G01X-169897Y840227D02*
Y831894D01*
G01Y843560D02*
X-170314Y843769D01*
Y844186D01*
X-169897Y844394D01*
X-169480Y844186D01*
Y843769D01*
X-169897Y843560D01*
G01X-157939Y831894D02*
Y840227D01*
G01Y838144D02*
X-157105Y839186D01*
X-155855Y840019D01*
X-154189Y840227D01*
X-152730Y840019D01*
X-151480Y839186D01*
X-150855Y837727D01*
Y831894D01*
G01X-142022Y837519D02*
X-135355D01*
X-135980Y838977D01*
X-137022Y839811D01*
X-138480Y840227D01*
X-139939Y840019D01*
X-141189Y839394D01*
X-142022Y837936D01*
X-142439Y836685D01*
Y835436D01*
X-142022Y834186D01*
X-140980Y832935D01*
X-139730Y832102D01*
X-138272Y831894D01*
X-136814Y832311D01*
X-135355Y833560D01*
G01X-107897Y844394D02*
Y831894D01*
G01X-110814Y840227D02*
X-104980D01*
G01X-95939Y831894D02*
Y844394D01*
G01Y838352D02*
X-94897Y839394D01*
X-93855Y840019D01*
X-92189Y840227D01*
X-90939Y840019D01*
X-89480Y839186D01*
X-88855Y837936D01*
Y831894D01*
G01X-80022Y837519D02*
X-73355D01*
X-73980Y838977D01*
X-75022Y839811D01*
X-76480Y840227D01*
X-77939Y840019D01*
X-79189Y839394D01*
X-80022Y837936D01*
X-80439Y836685D01*
Y835436D01*
X-80022Y834186D01*
X-78980Y832935D01*
X-77730Y832102D01*
X-76272Y831894D01*
X-74814Y832311D01*
X-73355Y833560D01*
G01X-64314Y831894D02*
Y840227D01*
G01Y838561D02*
X-63272Y839394D01*
X-62230Y840019D01*
X-60772Y840227D01*
X-59730Y840019D01*
X-58480Y839394D01*
G01X-52147Y831894D02*
Y840227D01*
G01Y837936D02*
X-51522Y838977D01*
X-50480Y839811D01*
X-49022Y840227D01*
X-47564Y839811D01*
X-46522Y838977D01*
X-45897Y837936D01*
Y831894D01*
G01Y837936D02*
X-45272Y838977D01*
X-44230Y839811D01*
X-42772Y840227D01*
X-41314Y839811D01*
X-40272Y838977D01*
X-39647Y837727D01*
Y831894D01*
G01X-26647D02*
Y840227D01*
G01Y838769D02*
X-27480Y839602D01*
X-28730Y840019D01*
X-30189Y840227D01*
X-31647Y839811D01*
X-32897Y838977D01*
X-33731Y837727D01*
X-34147Y836061D01*
X-33731Y834394D01*
X-32897Y833144D01*
X-31647Y832311D01*
X-30189Y831894D01*
X-28730Y832102D01*
X-27480Y832727D01*
X-26647Y833560D01*
G01X-14897Y831894D02*
Y844394D01*
G01X13186Y831894D02*
Y840227D01*
G01Y838561D02*
X14228Y839394D01*
X15270Y840019D01*
X16728Y840227D01*
X17770Y840019D01*
X19020Y839394D01*
G01X28478Y837519D02*
X35145D01*
X34520Y838977D01*
X33478Y839811D01*
X32020Y840227D01*
X30561Y840019D01*
X29311Y839394D01*
X28478Y837936D01*
X28061Y836685D01*
Y835436D01*
X28478Y834186D01*
X29520Y832935D01*
X30770Y832102D01*
X32228Y831894D01*
X33686Y832311D01*
X35145Y833560D01*
G01X47103Y831894D02*
Y844394D01*
G01X62603Y840227D02*
Y831894D01*
G01Y843560D02*
X62186Y843769D01*
Y844186D01*
X62603Y844394D01*
X63020Y844186D01*
Y843769D01*
X62603Y843560D01*
G01X74978Y837519D02*
X81645D01*
X81020Y838977D01*
X79978Y839811D01*
X78520Y840227D01*
X77061Y840019D01*
X75811Y839394D01*
X74978Y837936D01*
X74561Y836685D01*
Y835436D01*
X74978Y834186D01*
X76020Y832935D01*
X77270Y832102D01*
X78728Y831894D01*
X80186Y832311D01*
X81645Y833560D01*
G01X92353Y831894D02*
Y842519D01*
X92770Y843560D01*
X93603Y844186D01*
X94853Y844394D01*
X96103Y843977D01*
X96728Y842936D01*
G01X94228Y839394D02*
X90061D01*
G01X127936Y839186D02*
X126478Y840019D01*
X125228Y840227D01*
X123561Y839811D01*
X122311Y838977D01*
X121478Y837519D01*
X121269Y836061D01*
X121478Y834602D01*
X122311Y833352D01*
X123561Y832311D01*
X125228Y831894D01*
X126686Y832311D01*
X127936Y833144D01*
G01X140103Y831894D02*
X138853Y832102D01*
X137603Y832935D01*
X136769Y834394D01*
X136353Y836061D01*
X136769Y837727D01*
X137603Y839186D01*
X138853Y840019D01*
X140103Y840227D01*
X141353Y840019D01*
X142603Y839186D01*
X143436Y837727D01*
X143645Y836061D01*
X143436Y834394D01*
X142603Y832935D01*
X141353Y832102D01*
X140103Y831894D01*
G01X152061D02*
Y840227D01*
G01Y838144D02*
X152895Y839186D01*
X154145Y840019D01*
X155811Y840227D01*
X157270Y840019D01*
X158520Y839186D01*
X159145Y837727D01*
Y831894D01*
G01X167561D02*
Y840227D01*
G01Y838144D02*
X168395Y839186D01*
X169645Y840019D01*
X171311Y840227D01*
X172770Y840019D01*
X174020Y839186D01*
X174645Y837727D01*
Y831894D01*
G01X183478Y837519D02*
X190145D01*
X189520Y838977D01*
X188478Y839811D01*
X187020Y840227D01*
X185561Y840019D01*
X184311Y839394D01*
X183478Y837936D01*
X183061Y836685D01*
Y835436D01*
X183478Y834186D01*
X184520Y832935D01*
X185770Y832102D01*
X187228Y831894D01*
X188686Y832311D01*
X190145Y833560D01*
G01X205436Y839186D02*
X203978Y840019D01*
X202728Y840227D01*
X201061Y839811D01*
X199811Y838977D01*
X198978Y837519D01*
X198769Y836061D01*
X198978Y834602D01*
X199811Y833352D01*
X201061Y832311D01*
X202728Y831894D01*
X204186Y832311D01*
X205436Y833144D01*
G01X217603Y844394D02*
Y831894D01*
G01X214686Y840227D02*
X220520D01*
G01X451120Y403277D02*
X460286Y412444D01*
G01X455703Y414111D02*
Y401611D01*
G01X460286Y403277D02*
X451120Y412444D01*
G01X449453Y407861D02*
X461953D01*
G01X466620Y403277D02*
X475786Y412444D01*
G01X471203Y414111D02*
Y401611D01*
G01X475786Y403277D02*
X466620Y412444D01*
G01X464953Y407861D02*
X477453D01*
G01X482120Y403277D02*
X491286Y412444D01*
G01X486703Y414111D02*
Y401611D01*
G01X491286Y403277D02*
X482120Y412444D01*
G01X480453Y407861D02*
X492953D01*
G01X497620Y403277D02*
X506786Y412444D01*
G01X502203Y414111D02*
Y401611D01*
G01X506786Y403277D02*
X497620Y412444D01*
G01X495953Y407861D02*
X508453D01*
G01X517703Y403277D02*
X517286Y403486D01*
Y403902D01*
X517703Y404111D01*
X518120Y403902D01*
Y403486D01*
X517703Y403277D01*
G01Y408902D02*
X517286Y409111D01*
Y409527D01*
X517703Y409736D01*
X518120Y409527D01*
Y409111D01*
X517703Y408902D01*
G01X546203Y416194D02*
X551203D01*
G01X548703D02*
Y403694D01*
G01X546203D02*
X551203D01*
G01X561286Y400569D02*
X562745Y399736D01*
X564411Y399527D01*
X565870Y399736D01*
X567120Y400777D01*
X567953Y402236D01*
Y412027D01*
G01Y410361D02*
X567120Y411194D01*
X565870Y411819D01*
X564411Y412027D01*
X562745Y411611D01*
X561703Y410777D01*
X560869Y409319D01*
X560453Y407861D01*
X560661Y406610D01*
X561495Y405152D01*
X562745Y404111D01*
X564411Y403694D01*
X565661Y403902D01*
X567120Y404735D01*
X567953Y405569D01*
G01X576161Y403694D02*
Y412027D01*
G01Y409944D02*
X576995Y410986D01*
X578245Y411819D01*
X579911Y412027D01*
X581370Y411819D01*
X582620Y410986D01*
X583245Y409527D01*
Y403694D01*
G01X595203D02*
X593953Y403902D01*
X592703Y404735D01*
X591869Y406194D01*
X591453Y407861D01*
X591869Y409527D01*
X592703Y410986D01*
X593953Y411819D01*
X595203Y412027D01*
X596453Y411819D01*
X597703Y410986D01*
X598536Y409527D01*
X598745Y407861D01*
X598536Y406194D01*
X597703Y404735D01*
X596453Y403902D01*
X595203Y403694D01*
G01X607786D02*
Y412027D01*
G01Y410361D02*
X608828Y411194D01*
X609870Y411819D01*
X611328Y412027D01*
X612370Y411819D01*
X613620Y411194D01*
G01X623078Y409319D02*
X629745D01*
X629120Y410777D01*
X628078Y411611D01*
X626620Y412027D01*
X625161Y411819D01*
X623911Y411194D01*
X623078Y409736D01*
X622661Y408485D01*
Y407236D01*
X623078Y405986D01*
X624120Y404735D01*
X625370Y403902D01*
X626828Y403694D01*
X628286Y404111D01*
X629745Y405360D01*
G01X657203Y403694D02*
Y416194D01*
X654703Y413694D01*
G01Y403694D02*
X659703D01*
G01X681953D02*
Y412027D01*
G01Y409736D02*
X682578Y410777D01*
X683620Y411611D01*
X685078Y412027D01*
X686536Y411611D01*
X687578Y410777D01*
X688203Y409736D01*
Y403694D01*
G01Y409736D02*
X688828Y410777D01*
X689870Y411611D01*
X691328Y412027D01*
X692786Y411611D01*
X693828Y410777D01*
X694453Y409527D01*
Y403694D01*
G01X703703Y412027D02*
Y403694D01*
G01Y415360D02*
X703286Y415569D01*
Y415986D01*
X703703Y416194D01*
X704120Y415986D01*
Y415569D01*
X703703Y415360D01*
G01X719203Y403694D02*
Y416194D01*
G01X745620Y403694D02*
Y416194D01*
X749786D01*
X751453Y415569D01*
X752703Y414736D01*
X753745Y413486D01*
X754578Y412027D01*
X754786Y409944D01*
X754578Y407861D01*
X753745Y406402D01*
X752703Y405152D01*
X751453Y404319D01*
X749786Y403694D01*
X745620D01*
G01X762995Y407861D02*
X768411D01*
G01X785786Y415152D02*
X784536Y415777D01*
X783078Y416194D01*
X781411D01*
X779536Y415569D01*
X778078Y414527D01*
X777036Y413277D01*
X776203Y411194D01*
X775994Y409319D01*
X776411Y407444D01*
X777036Y406194D01*
X778286Y404944D01*
X779745Y404111D01*
X781203Y403694D01*
X782661D01*
X784120Y404111D01*
X785370Y404735D01*
X786412Y405569D01*
G01X796703Y403694D02*
X795036Y403902D01*
X793578Y404735D01*
X792328Y405986D01*
X791494Y407444D01*
X791078Y409111D01*
Y410777D01*
X791494Y412444D01*
X792328Y413902D01*
X793578Y415152D01*
X795036Y415986D01*
X796703Y416194D01*
X798370Y415986D01*
X799828Y415152D01*
X801078Y413902D01*
X801912Y412444D01*
X802328Y410777D01*
Y409111D01*
X801912Y407444D01*
X801078Y405986D01*
X799828Y404735D01*
X798370Y403902D01*
X796703Y403694D01*
G01X807620D02*
Y416194D01*
X811786D01*
X813453Y415569D01*
X814703Y414736D01*
X815745Y413486D01*
X816578Y412027D01*
X816786Y409944D01*
X816578Y407861D01*
X815745Y406402D01*
X814703Y405152D01*
X813453Y404319D01*
X811786Y403694D01*
X807620D01*
G01X831870D02*
X823536D01*
Y416194D01*
X831870D01*
G01X828536Y410152D02*
X823536D01*
G01X455311Y448594D02*
Y461094D01*
X464895Y448594D01*
Y461094D01*
G01X475603Y448594D02*
X474353Y448802D01*
X473103Y449635D01*
X472269Y451094D01*
X471853Y452761D01*
X472269Y454427D01*
X473103Y455886D01*
X474353Y456719D01*
X475603Y456927D01*
X476853Y456719D01*
X478103Y455886D01*
X478936Y454427D01*
X479145Y452761D01*
X478936Y451094D01*
X478103Y449635D01*
X476853Y448802D01*
X475603Y448594D01*
G01X491103Y461094D02*
Y448594D01*
G01X488186Y456927D02*
X494020D01*
G01X503478Y454219D02*
X510145D01*
X509520Y455677D01*
X508478Y456511D01*
X507020Y456927D01*
X505561Y456719D01*
X504311Y456094D01*
X503478Y454636D01*
X503061Y453385D01*
Y452136D01*
X503478Y450886D01*
X504520Y449635D01*
X505770Y448802D01*
X507228Y448594D01*
X508686Y449011D01*
X510145Y450260D01*
G01X518978Y450052D02*
X520020Y449219D01*
X521478Y448594D01*
X522728D01*
X523978Y449011D01*
X524811Y449635D01*
X525228Y450469D01*
X525020Y451719D01*
X524186Y452344D01*
X520436Y453594D01*
X519603Y455052D01*
X520020Y456094D01*
X520853Y456719D01*
X522103Y456927D01*
X523353Y456719D01*
X524603Y456094D01*
G01X537603Y448177D02*
X537186Y448386D01*
Y448802D01*
X537603Y449011D01*
X538020Y448802D01*
Y448386D01*
X537603Y448177D01*
G01Y453802D02*
X537186Y454011D01*
Y454427D01*
X537603Y454636D01*
X538020Y454427D01*
Y454011D01*
X537603Y453802D01*
G54D11*
G01X-216314Y631894D02*
X-222980D01*
Y641894D01*
X-216314D01*
G01X-218980Y637061D02*
X-222980D01*
G01X-211847Y631894D02*
X-204847Y641894D01*
G01X-211847D02*
X-204847Y631894D01*
G01X-197047Y631561D02*
X-197380Y631727D01*
Y632061D01*
X-197047Y632227D01*
X-196714Y632061D01*
Y631727D01*
X-197047Y631561D01*
G01Y636060D02*
X-197380Y636227D01*
Y636561D01*
X-197047Y636727D01*
X-196714Y636561D01*
Y636227D01*
X-197047Y636060D01*
G01X-177614Y631894D02*
Y641894D01*
X-171280D01*
G01X-173614Y637061D02*
X-177614D01*
G01X-166480Y641894D02*
Y631894D01*
X-159814D01*
G01X-156014D02*
X-151847Y641894D01*
X-147680Y631894D01*
G01X-149180Y635394D02*
X-154514D01*
G01X-144047Y633227D02*
X-142714Y632394D01*
X-141214Y631894D01*
X-139880D01*
X-138547Y632394D01*
X-137547Y633227D01*
X-137047Y634394D01*
X-137380Y635560D01*
X-138214Y636561D01*
X-139714Y637227D01*
X-141714Y637561D01*
X-142880Y638227D01*
X-143380Y639394D01*
X-143047Y640561D01*
X-142214Y641394D01*
X-141047Y641894D01*
X-139880D01*
X-138714Y641561D01*
X-137714Y640727D01*
G01X-132747Y631894D02*
Y641894D01*
G01X-125747D02*
Y631894D01*
G01Y636894D02*
X-132747D01*
G01X-106647Y641894D02*
Y631894D01*
G01X-110480Y641894D02*
X-102814D01*
G01X-98680Y631894D02*
Y641894D01*
X-94514D01*
X-93180Y641394D01*
X-92347Y640727D01*
X-92014Y639394D01*
X-92347Y638061D01*
X-93347Y637227D01*
X-94514Y636727D01*
X-98680D01*
G01X-94514D02*
X-92014Y631894D01*
G01X-84047D02*
Y641894D01*
X-86047Y639894D01*
G01Y631894D02*
X-82047D01*
G01X-72747Y641894D02*
X-74081Y641561D01*
X-75080Y640727D01*
X-75747Y639727D01*
X-76247Y638394D01*
X-76414Y636894D01*
X-76247Y635394D01*
X-75747Y634061D01*
X-75080Y633060D01*
X-74081Y632227D01*
X-72747Y631894D01*
X-71414Y632227D01*
X-70414Y633060D01*
X-69747Y634061D01*
X-69247Y635394D01*
X-69080Y636894D01*
X-69247Y638394D01*
X-69747Y639727D01*
X-70414Y640727D01*
X-71414Y641561D01*
X-72747Y641894D01*
G01X-65114Y633894D02*
X-64114Y632727D01*
X-62781Y632061D01*
X-61280Y631894D01*
X-59947Y632061D01*
X-58614Y632894D01*
X-57780Y633894D01*
X-57614Y634894D01*
X-57947Y636060D01*
X-59114Y636894D01*
X-60280Y637227D01*
X-61780D01*
G01X-60280D02*
X-59280Y637727D01*
X-58447Y638560D01*
X-58114Y639561D01*
X-58447Y640561D01*
X-59280Y641394D01*
X-60780Y641894D01*
X-62280Y641727D01*
X-63780Y641061D01*
G01X-55147Y628561D02*
X-45147D01*
G01X-41680Y633060D02*
X-40514Y632227D01*
X-39180Y631894D01*
X-37847Y632227D01*
X-36680Y633227D01*
X-35847Y634727D01*
X-35514Y636227D01*
Y638061D01*
X-35847Y639561D01*
X-36680Y640894D01*
X-37680Y641561D01*
X-38847Y641894D01*
X-40181Y641561D01*
X-41180Y640894D01*
X-41847Y639894D01*
X-42180Y638560D01*
X-41847Y637394D01*
X-41014Y636227D01*
X-40014Y635560D01*
X-38847Y635394D01*
X-37514Y635727D01*
X-36514Y636561D01*
X-35514Y638061D01*
G01X-31214Y633894D02*
X-30214Y632727D01*
X-28881Y632061D01*
X-27380Y631894D01*
X-26047Y632061D01*
X-24714Y632894D01*
X-23880Y633894D01*
X-23714Y634894D01*
X-24047Y636060D01*
X-25214Y636894D01*
X-26380Y637227D01*
X-27880D01*
G01X-26380D02*
X-25380Y637727D01*
X-24547Y638560D01*
X-24214Y639561D01*
X-24547Y640561D01*
X-25380Y641394D01*
X-26880Y641894D01*
X-28380Y641727D01*
X-29880Y641061D01*
G01X-21247Y628561D02*
X-11247D01*
G01X-8614Y633894D02*
X-7614Y632727D01*
X-6281Y632061D01*
X-4780Y631894D01*
X-3447Y632061D01*
X-2114Y632894D01*
X-1280Y633894D01*
X-1114Y634894D01*
X-1447Y636060D01*
X-2614Y636894D01*
X-3780Y637227D01*
X-5280D01*
G01X-3780D02*
X-2780Y637727D01*
X-1947Y638560D01*
X-1614Y639561D01*
X-1947Y640561D01*
X-2780Y641394D01*
X-4280Y641894D01*
X-5780Y641727D01*
X-7280Y641061D01*
G01X6353Y641894D02*
X5019Y641561D01*
X4020Y640727D01*
X3353Y639727D01*
X2853Y638394D01*
X2686Y636894D01*
X2853Y635394D01*
X3353Y634061D01*
X4020Y633060D01*
X5019Y632227D01*
X6353Y631894D01*
X7686Y632227D01*
X8686Y633060D01*
X9353Y634061D01*
X9853Y635394D01*
X10020Y636894D01*
X9853Y638394D01*
X9353Y639727D01*
X8686Y640727D01*
X7686Y641561D01*
X6353Y641894D01*
G01X17653Y631561D02*
X17320Y631727D01*
Y632061D01*
X17653Y632227D01*
X17986Y632061D01*
Y631727D01*
X17653Y631561D01*
G01Y636060D02*
X17320Y636227D01*
Y636561D01*
X17653Y636727D01*
X17986Y636561D01*
Y636227D01*
X17653Y636060D01*
G01X-209314Y773894D02*
X-208314Y772727D01*
X-206981Y772061D01*
X-205480Y771894D01*
X-204147Y772061D01*
X-202814Y772894D01*
X-201980Y773894D01*
X-201814Y774894D01*
X-202147Y776060D01*
X-203314Y776894D01*
X-204480Y777227D01*
X-205980D01*
G01X-204480D02*
X-203480Y777727D01*
X-202647Y778560D01*
X-202314Y779561D01*
X-202647Y780561D01*
X-203480Y781394D01*
X-204980Y781894D01*
X-206480Y781727D01*
X-207980Y781061D01*
G01X-194347Y771561D02*
X-194680Y771727D01*
Y772061D01*
X-194347Y772227D01*
X-194014Y772061D01*
Y771727D01*
X-194347Y771561D01*
G01X-205647Y803894D02*
Y813894D01*
X-207647Y811894D01*
G01Y803894D02*
X-203647D01*
G01X-194347Y803561D02*
X-194680Y803727D01*
Y804061D01*
X-194347Y804227D01*
X-194014Y804061D01*
Y803727D01*
X-194347Y803561D01*
G01X-174914Y803894D02*
Y813894D01*
X-168580D01*
G01X-170914Y809061D02*
X-174914D01*
G01X-163780Y813894D02*
Y803894D01*
X-157114D01*
G01X-153314D02*
X-149147Y813894D01*
X-144980Y803894D01*
G01X-146480Y807394D02*
X-151814D01*
G01X-141347Y805227D02*
X-140014Y804394D01*
X-138514Y803894D01*
X-137180D01*
X-135847Y804394D01*
X-134847Y805227D01*
X-134347Y806394D01*
X-134680Y807560D01*
X-135514Y808561D01*
X-137014Y809227D01*
X-139014Y809561D01*
X-140180Y810227D01*
X-140680Y811394D01*
X-140347Y812561D01*
X-139514Y813394D01*
X-138347Y813894D01*
X-137180D01*
X-136014Y813561D01*
X-135014Y812727D01*
G01X-130047Y803894D02*
Y813894D01*
G01X-123047D02*
Y803894D01*
G01Y808894D02*
X-130047D01*
G01X-103947Y813894D02*
Y803894D01*
G01X-107780Y813894D02*
X-100114D01*
G01X-96147Y803894D02*
Y813894D01*
G01X-89147D02*
Y803894D01*
G01Y808894D02*
X-96147D01*
G01X-85680Y803894D02*
Y813894D01*
X-81347Y805561D01*
X-77014Y813894D01*
Y803894D01*
G01X-73380Y813894D02*
Y803894D01*
X-66714D01*
G01X-58747D02*
Y813894D01*
X-60747Y811894D01*
G01Y803894D02*
X-56747D01*
G01X-47447Y813894D02*
X-48781Y813561D01*
X-49780Y812727D01*
X-50447Y811727D01*
X-50947Y810394D01*
X-51114Y808894D01*
X-50947Y807394D01*
X-50447Y806061D01*
X-49780Y805060D01*
X-48781Y804227D01*
X-47447Y803894D01*
X-46114Y804227D01*
X-45114Y805060D01*
X-44447Y806061D01*
X-43947Y807394D01*
X-43780Y808894D01*
X-43947Y810394D01*
X-44447Y811727D01*
X-45114Y812727D01*
X-46114Y813561D01*
X-47447Y813894D01*
G01X-24847Y803561D02*
X-25180Y803727D01*
Y804061D01*
X-24847Y804227D01*
X-24514Y804061D01*
Y803727D01*
X-24847Y803561D01*
G01Y808060D02*
X-25180Y808227D01*
Y808561D01*
X-24847Y808727D01*
X-24514Y808561D01*
Y808227D01*
X-24847Y808060D01*
G01X-5414Y803894D02*
Y813894D01*
X920D01*
G01X-1414Y809061D02*
X-5414D01*
G01X6220Y810560D02*
Y805894D01*
X6886Y804727D01*
X7886Y804061D01*
X9053Y803894D01*
X10220Y804061D01*
X11220Y804727D01*
X11886Y805894D01*
G01Y803894D02*
Y810560D01*
G01X20353Y803894D02*
Y813894D01*
G01X31653Y803894D02*
Y813894D01*
G01X56920Y809727D02*
X55753Y810394D01*
X54753Y810560D01*
X53420Y810227D01*
X52420Y809561D01*
X51753Y808394D01*
X51586Y807227D01*
X51753Y806061D01*
X52420Y805060D01*
X53420Y804227D01*
X54753Y803894D01*
X55920Y804227D01*
X56920Y804894D01*
G01X65553Y803894D02*
X64553Y804061D01*
X63553Y804727D01*
X62886Y805894D01*
X62553Y807227D01*
X62886Y808561D01*
X63553Y809727D01*
X64553Y810394D01*
X65553Y810560D01*
X66553Y810394D01*
X67553Y809727D01*
X68220Y808561D01*
X68386Y807227D01*
X68220Y805894D01*
X67553Y804727D01*
X66553Y804061D01*
X65553Y803894D01*
G01X74020D02*
Y810560D01*
G01Y808894D02*
X74686Y809727D01*
X75686Y810394D01*
X77020Y810560D01*
X78186Y810394D01*
X79186Y809727D01*
X79686Y808561D01*
Y803894D01*
G01X88153Y813894D02*
Y803894D01*
G01X85820Y810560D02*
X90486D01*
G01X102453Y803894D02*
Y810560D01*
G01Y809394D02*
X101786Y810061D01*
X100786Y810394D01*
X99620Y810560D01*
X98453Y810227D01*
X97453Y809561D01*
X96786Y808561D01*
X96453Y807227D01*
X96786Y805894D01*
X97453Y804894D01*
X98453Y804227D01*
X99620Y803894D01*
X100786Y804061D01*
X101786Y804561D01*
X102453Y805227D01*
G01X113420Y809727D02*
X112253Y810394D01*
X111253Y810560D01*
X109920Y810227D01*
X108920Y809561D01*
X108253Y808394D01*
X108086Y807227D01*
X108253Y806061D01*
X108920Y805060D01*
X109920Y804227D01*
X111253Y803894D01*
X112420Y804227D01*
X113420Y804894D01*
G01X122053Y813894D02*
Y803894D01*
G01X119720Y810560D02*
X124386D01*
G01X-208814Y796227D02*
X-207814Y797227D01*
X-206647Y797727D01*
X-205314Y797894D01*
X-203647Y797561D01*
X-202480Y796727D01*
X-202147Y795727D01*
X-202314Y794727D01*
X-202980Y793894D01*
X-206314Y792227D01*
X-207814Y791061D01*
X-208814Y789394D01*
X-209147Y787894D01*
X-202147D01*
G01X-194347Y787561D02*
X-194680Y787727D01*
Y788061D01*
X-194347Y788227D01*
X-194014Y788061D01*
Y787727D01*
X-194347Y787561D01*
G01X-143314Y137194D02*
X-149980D01*
Y147194D01*
X-143314D01*
G01X-145980Y142361D02*
X-149980D01*
G01X-135347Y136861D02*
X-135680Y137027D01*
Y137361D01*
X-135347Y137527D01*
X-135014Y137361D01*
Y137027D01*
X-135347Y136861D01*
G01Y141360D02*
X-135680Y141527D01*
Y141861D01*
X-135347Y142027D01*
X-135014Y141861D01*
Y141527D01*
X-135347Y141360D01*
G01X-160014Y111194D02*
X-166680D01*
Y121194D01*
X-160014D01*
G01X-162680Y116361D02*
X-166680D01*
G01X-155547Y111194D02*
X-148547Y121194D01*
G01X-155547D02*
X-148547Y111194D01*
G01X-140747Y110861D02*
X-141080Y111027D01*
Y111361D01*
X-140747Y111527D01*
X-140414Y111361D01*
Y111027D01*
X-140747Y110861D01*
G01Y115360D02*
X-141080Y115527D01*
Y115861D01*
X-140747Y116027D01*
X-140414Y115861D01*
Y115527D01*
X-140747Y115360D01*
G01X-121314Y111194D02*
Y121194D01*
X-114980D01*
G01X-117314Y116361D02*
X-121314D01*
G01X-110180Y121194D02*
Y111194D01*
X-103514D01*
G01X-99714D02*
X-95547Y121194D01*
X-91380Y111194D01*
G01X-92880Y114694D02*
X-98214D01*
G01X-87747Y112527D02*
X-86414Y111694D01*
X-84914Y111194D01*
X-83580D01*
X-82247Y111694D01*
X-81247Y112527D01*
X-80747Y113694D01*
X-81080Y114860D01*
X-81914Y115861D01*
X-83414Y116527D01*
X-85414Y116861D01*
X-86580Y117527D01*
X-87080Y118694D01*
X-86747Y119861D01*
X-85914Y120694D01*
X-84747Y121194D01*
X-83580D01*
X-82414Y120861D01*
X-81414Y120027D01*
G01X-76447Y111194D02*
Y121194D01*
G01X-69447D02*
Y111194D01*
G01Y116194D02*
X-76447D01*
G01X-50347Y121194D02*
Y111194D01*
G01X-54180Y121194D02*
X-46514D01*
G01X-42380Y111194D02*
Y121194D01*
X-38214D01*
X-36880Y120694D01*
X-36047Y120027D01*
X-35714Y118694D01*
X-36047Y117361D01*
X-37047Y116527D01*
X-38214Y116027D01*
X-42380D01*
G01X-38214D02*
X-35714Y111194D01*
G01X-30914Y115360D02*
X-29747Y116527D01*
X-28747Y117194D01*
X-27414Y117527D01*
X-26247Y117194D01*
X-25414Y116527D01*
X-24747Y115527D01*
X-24580Y114361D01*
X-24747Y113361D01*
X-25414Y112360D01*
X-26414Y111527D01*
X-27580Y111194D01*
X-28914Y111527D01*
X-30080Y112527D01*
X-30747Y114027D01*
X-30914Y115694D01*
X-30580Y117860D01*
X-30080Y119027D01*
X-29247Y120194D01*
X-28080Y121027D01*
X-26914Y121194D01*
X-25747Y120861D01*
X-24914Y120027D01*
G01X-16447Y121194D02*
X-17781Y120861D01*
X-18780Y120027D01*
X-19447Y119027D01*
X-19947Y117694D01*
X-20114Y116194D01*
X-19947Y114694D01*
X-19447Y113361D01*
X-18780Y112360D01*
X-17781Y111527D01*
X-16447Y111194D01*
X-15114Y111527D01*
X-14114Y112360D01*
X-13447Y113361D01*
X-12947Y114694D01*
X-12780Y116194D01*
X-12947Y117694D01*
X-13447Y119027D01*
X-14114Y120027D01*
X-15114Y120861D01*
X-16447Y121194D01*
G01X-8647Y111194D02*
X-1647Y121194D01*
G01X-8647D02*
X-1647Y111194D01*
G01X6153D02*
Y121194D01*
X4153Y119194D01*
G01Y111194D02*
X8153D01*
G01X17453D02*
Y121194D01*
X15453Y119194D01*
G01Y111194D02*
X19453D01*
G01X25920Y112360D02*
X27086Y111527D01*
X28420Y111194D01*
X29753Y111527D01*
X30920Y112527D01*
X31753Y114027D01*
X32086Y115527D01*
Y117361D01*
X31753Y118861D01*
X30920Y120194D01*
X29920Y120861D01*
X28753Y121194D01*
X27419Y120861D01*
X26420Y120194D01*
X25753Y119194D01*
X25420Y117860D01*
X25753Y116694D01*
X26586Y115527D01*
X27586Y114860D01*
X28753Y114694D01*
X30086Y115027D01*
X31086Y115861D01*
X32086Y117361D01*
G01X35053Y107861D02*
X45053D01*
G01X48186Y119527D02*
X49186Y120527D01*
X50353Y121027D01*
X51686Y121194D01*
X53353Y120861D01*
X54520Y120027D01*
X54853Y119027D01*
X54686Y118027D01*
X54020Y117194D01*
X50686Y115527D01*
X49186Y114361D01*
X48186Y112694D01*
X47853Y111194D01*
X54853D01*
G01X62653Y121194D02*
X61319Y120861D01*
X60320Y120027D01*
X59653Y119027D01*
X59153Y117694D01*
X58986Y116194D01*
X59153Y114694D01*
X59653Y113361D01*
X60320Y112360D01*
X61319Y111527D01*
X62653Y111194D01*
X63986Y111527D01*
X64986Y112360D01*
X65653Y113361D01*
X66153Y114694D01*
X66320Y116194D01*
X66153Y117694D01*
X65653Y119027D01*
X64986Y120027D01*
X63986Y120861D01*
X62653Y121194D01*
G01X70453Y111194D02*
X77453Y121194D01*
G01X70453D02*
X77453Y111194D01*
G01X81586Y113194D02*
X82586Y112027D01*
X83919Y111361D01*
X85420Y111194D01*
X86753Y111361D01*
X88086Y112194D01*
X88920Y113194D01*
X89086Y114194D01*
X88753Y115360D01*
X87586Y116194D01*
X86420Y116527D01*
X84920D01*
G01X86420D02*
X87420Y117027D01*
X88253Y117860D01*
X88586Y118861D01*
X88253Y119861D01*
X87420Y120694D01*
X85920Y121194D01*
X84420Y121027D01*
X82920Y120361D01*
G01X96553Y121194D02*
X95219Y120861D01*
X94220Y120027D01*
X93553Y119027D01*
X93053Y117694D01*
X92886Y116194D01*
X93053Y114694D01*
X93553Y113361D01*
X94220Y112360D01*
X95219Y111527D01*
X96553Y111194D01*
X97886Y111527D01*
X98886Y112360D01*
X99553Y113361D01*
X100053Y114694D01*
X100220Y116194D01*
X100053Y117694D01*
X99553Y119027D01*
X98886Y120027D01*
X97886Y120861D01*
X96553Y121194D01*
G01X-170380Y160994D02*
Y170994D01*
X-162714Y160994D01*
Y170994D01*
G01X-159414Y160994D02*
X-155247Y170994D01*
X-151080Y160994D01*
G01X-152580Y164494D02*
X-157914D01*
G01X-148280Y160994D02*
Y170994D01*
X-143947Y162661D01*
X-139614Y170994D01*
Y160994D01*
G01X-129314D02*
X-135980D01*
Y170994D01*
X-129314D01*
G01X-131980Y166161D02*
X-135980D01*
G01X-121347Y160661D02*
X-121680Y160827D01*
Y161161D01*
X-121347Y161327D01*
X-121014Y161161D01*
Y160827D01*
X-121347Y160661D01*
G01Y165160D02*
X-121680Y165327D01*
Y165661D01*
X-121347Y165827D01*
X-121014Y165661D01*
Y165327D01*
X-121347Y165160D01*
G01X-98747Y170994D02*
Y160994D01*
G01X-102580Y170994D02*
X-94914D01*
G01X-90780Y160994D02*
Y170994D01*
X-86614D01*
X-85280Y170494D01*
X-84447Y169827D01*
X-84114Y168494D01*
X-84447Y167161D01*
X-85447Y166327D01*
X-86614Y165827D01*
X-90780D01*
G01X-86614D02*
X-84114Y160994D01*
G01X-80314D02*
X-76147Y170994D01*
X-71980Y160994D01*
G01X-73480Y164494D02*
X-78814D01*
G01X-68347Y160994D02*
X-61347Y170994D01*
G01X-68347D02*
X-61347Y160994D01*
G01X-52214Y166327D02*
X-51547Y166827D01*
X-51047Y167660D01*
X-50714Y168827D01*
X-51047Y169827D01*
X-51714Y170494D01*
X-52880Y170994D01*
X-57380D01*
Y160994D01*
X-51880D01*
X-50714Y161661D01*
X-50047Y162661D01*
X-49714Y163827D01*
X-50047Y164994D01*
X-51047Y165994D01*
X-52214Y166327D01*
X-57380D01*
G01X-47247Y157661D02*
X-37247D01*
G01X-27280Y170161D02*
X-28280Y170661D01*
X-29447Y170994D01*
X-30780D01*
X-32281Y170494D01*
X-33447Y169661D01*
X-34280Y168661D01*
X-34947Y166994D01*
X-35114Y165494D01*
X-34780Y163994D01*
X-34280Y162994D01*
X-33280Y161994D01*
X-32114Y161327D01*
X-30947Y160994D01*
X-29780D01*
X-28614Y161327D01*
X-27614Y161827D01*
X-26780Y162494D01*
G01X-23147Y160994D02*
X-16147Y170994D01*
G01X-23147D02*
X-16147Y160994D01*
G01X-12014D02*
Y170994D01*
X-8680D01*
X-7347Y170494D01*
X-6347Y169827D01*
X-5514Y168827D01*
X-4847Y167660D01*
X-4680Y165994D01*
X-4847Y164327D01*
X-5514Y163161D01*
X-6347Y162160D01*
X-7347Y161494D01*
X-8680Y160994D01*
X-12014D01*
G01X-130814Y226594D02*
X-137480D01*
Y236594D01*
X-130814D01*
G01X-133480Y231761D02*
X-137480D01*
G01X-144114Y305594D02*
Y315594D01*
X-140780D01*
X-139447Y315094D01*
X-138447Y314427D01*
X-137614Y313427D01*
X-136947Y312260D01*
X-136780Y310594D01*
X-136947Y308927D01*
X-137614Y307761D01*
X-138447Y306760D01*
X-139447Y306094D01*
X-140780Y305594D01*
X-144114D01*
G01X-132414Y427194D02*
X-139080D01*
Y437194D01*
X-132414D01*
G01X-135080Y432361D02*
X-139080D01*
G01X-127780Y437194D02*
Y427194D01*
X-121114D01*
G01X-116480Y437194D02*
Y427194D01*
X-109814D01*
G01X-103847Y437194D02*
X-99847D01*
G01X-101847D02*
Y427194D01*
G01X-103847D02*
X-99847D01*
G01X-93880D02*
Y437194D01*
X-89880D01*
X-88547Y436694D01*
X-87547Y435527D01*
X-87214Y434194D01*
X-87547Y432861D01*
X-88380Y431861D01*
X-89880Y431360D01*
X-93880D01*
G01X-82747Y428527D02*
X-81414Y427694D01*
X-79914Y427194D01*
X-78580D01*
X-77247Y427694D01*
X-76247Y428527D01*
X-75747Y429694D01*
X-76080Y430860D01*
X-76914Y431861D01*
X-78414Y432527D01*
X-80414Y432861D01*
X-81580Y433527D01*
X-82080Y434694D01*
X-81747Y435861D01*
X-80914Y436694D01*
X-79747Y437194D01*
X-78580D01*
X-77414Y436861D01*
X-76414Y436027D01*
G01X-64614Y427194D02*
X-71280D01*
Y437194D01*
X-64614D01*
G01X-67280Y432361D02*
X-71280D01*
G01X-45347Y437194D02*
Y427194D01*
G01X-49180Y437194D02*
X-41514D01*
G01X-36880Y427194D02*
Y437194D01*
G01Y432361D02*
X-36047Y433194D01*
X-35214Y433694D01*
X-33880Y433860D01*
X-32880Y433694D01*
X-31714Y433027D01*
X-31214Y432027D01*
Y427194D01*
G01X-25247Y431694D02*
X-19914D01*
X-20414Y432861D01*
X-21247Y433527D01*
X-22414Y433860D01*
X-23580Y433694D01*
X-24580Y433194D01*
X-25247Y432027D01*
X-25580Y431027D01*
Y430027D01*
X-25247Y429027D01*
X-24414Y428027D01*
X-23414Y427361D01*
X-22247Y427194D01*
X-21080Y427527D01*
X-19914Y428527D01*
G01X-13780Y427194D02*
Y433860D01*
G01Y432527D02*
X-12947Y433194D01*
X-12114Y433694D01*
X-10947Y433860D01*
X-10114Y433694D01*
X-9114Y433194D01*
G01X-5147Y427194D02*
Y433860D01*
G01Y432027D02*
X-4647Y432861D01*
X-3814Y433527D01*
X-2647Y433860D01*
X-1481Y433527D01*
X-647Y432861D01*
X-147Y432027D01*
Y427194D01*
G01Y432027D02*
X353Y432861D01*
X1186Y433527D01*
X2353Y433860D01*
X3520Y433527D01*
X4353Y432861D01*
X4853Y431861D01*
Y427194D01*
G01X14153D02*
Y433860D01*
G01Y432694D02*
X13486Y433361D01*
X12486Y433694D01*
X11320Y433860D01*
X10153Y433527D01*
X9153Y432861D01*
X8486Y431861D01*
X8153Y430527D01*
X8486Y429194D01*
X9153Y428194D01*
X10153Y427527D01*
X11320Y427194D01*
X12486Y427361D01*
X13486Y427861D01*
X14153Y428527D01*
G01X22453Y427194D02*
Y437194D01*
G01X-133947Y669094D02*
X-129947D01*
G01X-131947D02*
Y659094D01*
G01X-133947D02*
X-129947D01*
G01X-123480D02*
Y665760D01*
G01Y664094D02*
X-122814Y664927D01*
X-121814Y665594D01*
X-120480Y665760D01*
X-119314Y665594D01*
X-118314Y664927D01*
X-117814Y663761D01*
Y659094D01*
G01X-112180D02*
Y665760D01*
G01Y664094D02*
X-111514Y664927D01*
X-110514Y665594D01*
X-109180Y665760D01*
X-108014Y665594D01*
X-107014Y664927D01*
X-106514Y663761D01*
Y659094D01*
G01X-100547Y663594D02*
X-95214D01*
X-95714Y664761D01*
X-96547Y665427D01*
X-97714Y665760D01*
X-98880Y665594D01*
X-99880Y665094D01*
X-100547Y663927D01*
X-100880Y662927D01*
Y661927D01*
X-100547Y660927D01*
X-99714Y659927D01*
X-98714Y659261D01*
X-97547Y659094D01*
X-96380Y659427D01*
X-95214Y660427D01*
G01X-89080Y659094D02*
Y665760D01*
G01Y664427D02*
X-88247Y665094D01*
X-87414Y665594D01*
X-86247Y665760D01*
X-85414Y665594D01*
X-84414Y665094D01*
G01X-67814Y659094D02*
Y669094D01*
X-64480D01*
X-63147Y668594D01*
X-62147Y667927D01*
X-61314Y666927D01*
X-60647Y665760D01*
X-60480Y664094D01*
X-60647Y662427D01*
X-61314Y661261D01*
X-62147Y660260D01*
X-63147Y659594D01*
X-64480Y659094D01*
X-67814D01*
G01X-52847Y665760D02*
Y659094D01*
G01Y668427D02*
X-53180Y668594D01*
Y668927D01*
X-52847Y669094D01*
X-52514Y668927D01*
Y668594D01*
X-52847Y668427D01*
G01X-38547Y659094D02*
Y665760D01*
G01Y664594D02*
X-39214Y665261D01*
X-40214Y665594D01*
X-41380Y665760D01*
X-42547Y665427D01*
X-43547Y664761D01*
X-44214Y663761D01*
X-44547Y662427D01*
X-44214Y661094D01*
X-43547Y660094D01*
X-42547Y659427D01*
X-41380Y659094D01*
X-40214Y659261D01*
X-39214Y659761D01*
X-38547Y660427D01*
G01X-35247Y659094D02*
Y665760D01*
G01Y663927D02*
X-34747Y664761D01*
X-33914Y665427D01*
X-32747Y665760D01*
X-31581Y665427D01*
X-30747Y664761D01*
X-30247Y663927D01*
Y659094D01*
G01Y663927D02*
X-29747Y664761D01*
X-28914Y665427D01*
X-27747Y665760D01*
X-26580Y665427D01*
X-25747Y664761D01*
X-25247Y663761D01*
Y659094D01*
G01X-21447Y663594D02*
X-16114D01*
X-16614Y664761D01*
X-17447Y665427D01*
X-18614Y665760D01*
X-19780Y665594D01*
X-20780Y665094D01*
X-21447Y663927D01*
X-21780Y662927D01*
Y661927D01*
X-21447Y660927D01*
X-20614Y659927D01*
X-19614Y659261D01*
X-18447Y659094D01*
X-17280Y659427D01*
X-16114Y660427D01*
G01X-7647Y669094D02*
Y659094D01*
G01X-9980Y665760D02*
X-5314D01*
G01X1153Y663594D02*
X6486D01*
X5986Y664761D01*
X5153Y665427D01*
X3986Y665760D01*
X2820Y665594D01*
X1820Y665094D01*
X1153Y663927D01*
X820Y662927D01*
Y661927D01*
X1153Y660927D01*
X1986Y659927D01*
X2986Y659261D01*
X4153Y659094D01*
X5320Y659427D01*
X6486Y660427D01*
G01X12620Y659094D02*
Y665760D01*
G01Y664427D02*
X13453Y665094D01*
X14286Y665594D01*
X15453Y665760D01*
X16286Y665594D01*
X17286Y665094D01*
G01X-176647Y795894D02*
X-174314Y785894D01*
X-171647Y795894D01*
X-168980Y785894D01*
X-166647Y795894D01*
G01X-160347Y792560D02*
Y785894D01*
G01Y795227D02*
X-160680Y795394D01*
Y795727D01*
X-160347Y795894D01*
X-160014Y795727D01*
Y795394D01*
X-160347Y795227D01*
G01X-151547Y787060D02*
X-150714Y786394D01*
X-149547Y785894D01*
X-148547D01*
X-147547Y786227D01*
X-146880Y786727D01*
X-146547Y787394D01*
X-146714Y788394D01*
X-147380Y788894D01*
X-150381Y789894D01*
X-151047Y791061D01*
X-150714Y791894D01*
X-150047Y792394D01*
X-149047Y792560D01*
X-148047Y792394D01*
X-147047Y791894D01*
G01X-137747Y795894D02*
Y785894D01*
G01X-140080Y792560D02*
X-135414D01*
G01X-128780Y785894D02*
Y792560D01*
G01Y791227D02*
X-127947Y791894D01*
X-127114Y792394D01*
X-125947Y792560D01*
X-125114Y792394D01*
X-124114Y791894D01*
G01X-115147Y785894D02*
X-116147Y786061D01*
X-117147Y786727D01*
X-117814Y787894D01*
X-118147Y789227D01*
X-117814Y790561D01*
X-117147Y791727D01*
X-116147Y792394D01*
X-115147Y792560D01*
X-114147Y792394D01*
X-113147Y791727D01*
X-112480Y790561D01*
X-112314Y789227D01*
X-112480Y787894D01*
X-113147Y786727D01*
X-114147Y786061D01*
X-115147Y785894D01*
G01X-106680D02*
Y792560D01*
G01Y790894D02*
X-106014Y791727D01*
X-105014Y792394D01*
X-103680Y792560D01*
X-102514Y792394D01*
X-101514Y791727D01*
X-101014Y790561D01*
Y785894D01*
G01X-81247Y795894D02*
Y785894D01*
G01X-85080Y795894D02*
X-77414D01*
G01X-73447Y785894D02*
Y795894D01*
G01X-66447D02*
Y785894D01*
G01Y790894D02*
X-73447D01*
G01X-62980Y785894D02*
Y795894D01*
X-58647Y787561D01*
X-54314Y795894D01*
Y785894D01*
G01X-50680Y795894D02*
Y785894D01*
X-44014D01*
G01X-21747Y795894D02*
Y785894D01*
G01Y787394D02*
X-22414Y786561D01*
X-23414Y786061D01*
X-24580Y785894D01*
X-25914Y786227D01*
X-26914Y787060D01*
X-27580Y788061D01*
X-27747Y789227D01*
X-27580Y790394D01*
X-26914Y791394D01*
X-25914Y792227D01*
X-24580Y792560D01*
X-23414Y792394D01*
X-22580Y792061D01*
X-21747Y791394D01*
G01X-15947Y790394D02*
X-10614D01*
X-11114Y791561D01*
X-11947Y792227D01*
X-13114Y792560D01*
X-14280Y792394D01*
X-15280Y791894D01*
X-15947Y790727D01*
X-16280Y789727D01*
Y788727D01*
X-15947Y787727D01*
X-15114Y786727D01*
X-14114Y786061D01*
X-12947Y785894D01*
X-11780Y786227D01*
X-10614Y787227D01*
G01X-3147Y785894D02*
Y794394D01*
X-2814Y795227D01*
X-2147Y795727D01*
X-1147Y795894D01*
X-147Y795561D01*
X353Y794727D01*
G01X-1647Y791894D02*
X-4980D01*
G01X12153Y785894D02*
Y792560D01*
G01Y791394D02*
X11486Y792061D01*
X10486Y792394D01*
X9320Y792560D01*
X8153Y792227D01*
X7153Y791561D01*
X6486Y790561D01*
X6153Y789227D01*
X6486Y787894D01*
X7153Y786894D01*
X8153Y786227D01*
X9320Y785894D01*
X10486Y786061D01*
X11486Y786561D01*
X12153Y787227D01*
G01X17620Y792560D02*
Y787894D01*
X18286Y786727D01*
X19286Y786061D01*
X20453Y785894D01*
X21620Y786061D01*
X22620Y786727D01*
X23286Y787894D01*
G01Y785894D02*
Y792560D01*
G01X31753Y785894D02*
Y795894D01*
G01X43053D02*
Y785894D01*
G01X40720Y792560D02*
X45386D01*
G01X65653Y795894D02*
Y785894D01*
G01X63320Y792560D02*
X67986D01*
G01X73453Y782894D02*
X74453Y782561D01*
X75786Y782894D01*
X76620Y783561D01*
X77286Y784394D01*
X78286Y787060D01*
X80453Y792560D01*
G01X75120D02*
X78286Y787060D01*
G01X85253Y782561D02*
Y792560D01*
G01Y791061D02*
X86086Y791894D01*
X86919Y792394D01*
X88253Y792560D01*
X89420Y792394D01*
X90586Y791561D01*
X91086Y790394D01*
X91253Y789227D01*
X91086Y788061D01*
X90586Y786894D01*
X89586Y786227D01*
X88253Y785894D01*
X87086Y786061D01*
X85920Y786561D01*
X85253Y787227D01*
G01X97053Y790394D02*
X102386D01*
X101886Y791561D01*
X101053Y792227D01*
X99886Y792560D01*
X98720Y792394D01*
X97720Y791894D01*
X97053Y790727D01*
X96720Y789727D01*
Y788727D01*
X97053Y787727D01*
X97886Y786727D01*
X98886Y786061D01*
X100053Y785894D01*
X101220Y786227D01*
X102386Y787227D01*
G01X-95314Y136894D02*
X-101980D01*
Y146894D01*
X-95314D01*
G01X-97980Y142061D02*
X-101980D01*
G01X-89514Y138727D02*
X-85180D01*
G01Y141727D02*
X-89514D01*
G01X-79714Y138394D02*
X-78714Y137561D01*
X-77547Y137061D01*
X-76047Y136894D01*
X-74547Y137227D01*
X-73380Y137894D01*
X-72547Y139061D01*
X-72380Y140394D01*
X-72714Y141727D01*
X-73547Y142561D01*
X-74714Y143227D01*
X-75880Y143394D01*
X-77047Y143227D01*
X-78547Y142561D01*
X-78047Y146894D01*
X-73547D01*
G01X-57780Y136894D02*
Y146894D01*
X-53447Y138561D01*
X-49114Y146894D01*
Y136894D01*
G01X-44147Y146894D02*
X-40147D01*
G01X-42147D02*
Y136894D01*
G01X-44147D02*
X-40147D01*
G01X-34180Y146894D02*
Y136894D01*
X-27514D01*
G01X-23047Y138227D02*
X-21714Y137394D01*
X-20214Y136894D01*
X-18880D01*
X-17547Y137394D01*
X-16547Y138227D01*
X-16047Y139394D01*
X-16380Y140560D01*
X-17214Y141561D01*
X-18714Y142227D01*
X-20714Y142561D01*
X-21880Y143227D01*
X-22380Y144394D01*
X-22047Y145561D01*
X-21214Y146394D01*
X-20047Y146894D01*
X-18880D01*
X-17714Y146561D01*
X-16714Y145727D01*
G01X2220Y133561D02*
X553Y135227D01*
X-280Y136894D01*
Y143560D01*
X553Y145227D01*
X2220Y146894D01*
G01X17353Y136894D02*
Y143560D01*
G01Y142394D02*
X16686Y143061D01*
X15686Y143394D01*
X14520Y143560D01*
X13353Y143227D01*
X12353Y142561D01*
X11686Y141561D01*
X11353Y140227D01*
X11686Y138894D01*
X12353Y137894D01*
X13353Y137227D01*
X14520Y136894D01*
X15686Y137061D01*
X16686Y137561D01*
X17353Y138227D01*
G01X25653Y136894D02*
Y146894D01*
G01X32786Y143560D02*
X34786Y136894D01*
X36953Y143560D01*
X39120Y136894D01*
X41120Y143560D01*
G01X51253Y136894D02*
Y143560D01*
G01Y142394D02*
X50586Y143061D01*
X49586Y143394D01*
X48420Y143560D01*
X47253Y143227D01*
X46253Y142561D01*
X45586Y141561D01*
X45253Y140227D01*
X45586Y138894D01*
X46253Y137894D01*
X47253Y137227D01*
X48420Y136894D01*
X49586Y137061D01*
X50586Y137561D01*
X51253Y138227D01*
G01X56053Y133894D02*
X57053Y133561D01*
X58386Y133894D01*
X59220Y134561D01*
X59886Y135394D01*
X60886Y138060D01*
X63053Y143560D01*
G01X57720D02*
X60886Y138060D01*
G01X68353D02*
X69186Y137394D01*
X70353Y136894D01*
X71353D01*
X72353Y137227D01*
X73020Y137727D01*
X73353Y138394D01*
X73186Y139394D01*
X72520Y139894D01*
X69519Y140894D01*
X68853Y142061D01*
X69186Y142894D01*
X69853Y143394D01*
X70853Y143560D01*
X71853Y143394D01*
X72853Y142894D01*
G01X90620Y136894D02*
Y146894D01*
G01X95953Y143560D02*
X90620Y139727D01*
G01X92786Y141227D02*
X96286Y136894D01*
G01X102253Y141394D02*
X107586D01*
X107086Y142561D01*
X106253Y143227D01*
X105086Y143560D01*
X103920Y143394D01*
X102920Y142894D01*
X102253Y141727D01*
X101920Y140727D01*
Y139727D01*
X102253Y138727D01*
X103086Y137727D01*
X104086Y137061D01*
X105253Y136894D01*
X106420Y137227D01*
X107586Y138227D01*
G01X113553Y141394D02*
X118886D01*
X118386Y142561D01*
X117553Y143227D01*
X116386Y143560D01*
X115220Y143394D01*
X114220Y142894D01*
X113553Y141727D01*
X113220Y140727D01*
Y139727D01*
X113553Y138727D01*
X114386Y137727D01*
X115386Y137061D01*
X116553Y136894D01*
X117720Y137227D01*
X118886Y138227D01*
G01X124353Y133561D02*
Y143560D01*
G01Y142061D02*
X125186Y142894D01*
X126019Y143394D01*
X127353Y143560D01*
X128520Y143394D01*
X129686Y142561D01*
X130186Y141394D01*
X130353Y140227D01*
X130186Y139061D01*
X129686Y137894D01*
X128686Y137227D01*
X127353Y136894D01*
X126186Y137061D01*
X125020Y137561D01*
X124353Y138227D01*
G01X146286Y138394D02*
X147286Y137561D01*
X148453Y137061D01*
X149953Y136894D01*
X151453Y137227D01*
X152620Y137894D01*
X153453Y139061D01*
X153620Y140394D01*
X153286Y141727D01*
X152453Y142561D01*
X151286Y143227D01*
X150120Y143394D01*
X148953Y143227D01*
X147453Y142561D01*
X147953Y146894D01*
X152453D01*
G01X167553Y136894D02*
Y143560D01*
G01Y141727D02*
X168053Y142561D01*
X168886Y143227D01*
X170053Y143560D01*
X171219Y143227D01*
X172053Y142561D01*
X172553Y141727D01*
Y136894D01*
G01Y141727D02*
X173053Y142561D01*
X173886Y143227D01*
X175053Y143560D01*
X176220Y143227D01*
X177053Y142561D01*
X177553Y141561D01*
Y136894D01*
G01X183853Y143560D02*
Y136894D01*
G01Y146227D02*
X183520Y146394D01*
Y146727D01*
X183853Y146894D01*
X184186Y146727D01*
Y146394D01*
X183853Y146227D01*
G01X195153Y136894D02*
Y146894D01*
G01X203953Y138060D02*
X204786Y137394D01*
X205953Y136894D01*
X206953D01*
X207953Y137227D01*
X208620Y137727D01*
X208953Y138394D01*
X208786Y139394D01*
X208120Y139894D01*
X205119Y140894D01*
X204453Y142061D01*
X204786Y142894D01*
X205453Y143394D01*
X206453Y143560D01*
X207453Y143394D01*
X208453Y142894D01*
G01X218586Y133561D02*
X220253Y135227D01*
X221086Y136894D01*
Y143560D01*
X220253Y145227D01*
X218586Y146894D01*
G01X-62580Y209261D02*
X-63580Y209761D01*
X-64747Y210094D01*
X-66080D01*
X-67581Y209594D01*
X-68747Y208761D01*
X-69580Y207761D01*
X-70247Y206094D01*
X-70414Y204594D01*
X-70080Y203094D01*
X-69580Y202094D01*
X-68580Y201094D01*
X-67414Y200427D01*
X-66247Y200094D01*
X-65080D01*
X-63914Y200427D01*
X-62914Y200927D01*
X-62080Y201594D01*
G01X-70714Y397694D02*
X-66547Y407694D01*
X-62380Y397694D01*
G01X-63880Y401194D02*
X-69214D01*
G01X2386Y311427D02*
X3053Y311927D01*
X3553Y312760D01*
X3886Y313927D01*
X3553Y314927D01*
X2886Y315594D01*
X1720Y316094D01*
X-2780D01*
Y306094D01*
X2720D01*
X3886Y306761D01*
X4553Y307761D01*
X4886Y308927D01*
X4553Y310094D01*
X3553Y311094D01*
X2386Y311427D01*
X-2780D01*
G01X-39157Y716574D02*
X-35824D01*
Y713574D01*
X-36824Y712574D01*
X-37990Y711907D01*
X-39657Y711574D01*
X-41324Y711907D01*
X-42490Y712574D01*
X-43490Y713574D01*
X-44157Y714741D01*
X-44490Y716074D01*
Y717241D01*
X-44157Y718240D01*
X-43490Y719407D01*
X-42490Y720407D01*
X-41491Y721074D01*
X-40157Y721574D01*
X-38990D01*
X-37657Y721241D01*
X-36657Y720574D01*
G01X-25857Y711574D02*
Y718240D01*
G01Y717074D02*
X-26524Y717741D01*
X-27524Y718074D01*
X-28690Y718240D01*
X-29857Y717907D01*
X-30857Y717241D01*
X-31524Y716241D01*
X-31857Y714907D01*
X-31524Y713574D01*
X-30857Y712574D01*
X-29857Y711907D01*
X-28690Y711574D01*
X-27524Y711741D01*
X-26524Y712241D01*
X-25857Y712907D01*
G01X-20557Y708241D02*
Y718240D01*
G01Y716741D02*
X-19724Y717574D01*
X-18891Y718074D01*
X-17557Y718240D01*
X-16390Y718074D01*
X-15224Y717241D01*
X-14724Y716074D01*
X-14557Y714907D01*
X-14724Y713741D01*
X-15224Y712574D01*
X-16224Y711907D01*
X-17557Y711574D01*
X-18724Y711741D01*
X-19890Y712241D01*
X-20557Y712907D01*
G01X43Y721574D02*
X2376Y711574D01*
X5043Y721574D01*
X7710Y711574D01*
X10043Y721574D01*
G01X16343Y718240D02*
Y711574D01*
G01Y720907D02*
X16010Y721074D01*
Y721407D01*
X16343Y721574D01*
X16676Y721407D01*
Y721074D01*
X16343Y720907D01*
G01X30643Y721574D02*
Y711574D01*
G01Y713074D02*
X29976Y712241D01*
X28976Y711741D01*
X27810Y711574D01*
X26476Y711907D01*
X25476Y712740D01*
X24810Y713741D01*
X24643Y714907D01*
X24810Y716074D01*
X25476Y717074D01*
X26476Y717907D01*
X27810Y718240D01*
X28976Y718074D01*
X29810Y717741D01*
X30643Y717074D01*
G01X38943Y721574D02*
Y711574D01*
G01X36610Y718240D02*
X41276D01*
G01X47410Y711574D02*
Y721574D01*
G01Y716741D02*
X48243Y717574D01*
X49076Y718074D01*
X50410Y718240D01*
X51410Y718074D01*
X52576Y717407D01*
X53076Y716407D01*
Y711574D01*
G01X-36717Y760174D02*
X-38051Y760341D01*
X-39217Y761007D01*
X-40217Y762007D01*
X-40884Y763174D01*
X-41217Y764507D01*
Y765841D01*
X-40884Y767174D01*
X-40217Y768341D01*
X-39217Y769341D01*
X-38051Y770007D01*
X-36717Y770174D01*
X-35384Y770007D01*
X-34217Y769341D01*
X-33217Y768341D01*
X-32550Y767174D01*
X-32217Y765841D01*
Y764507D01*
X-32550Y763174D01*
X-33217Y762007D01*
X-34217Y761007D01*
X-35384Y760341D01*
X-36717Y760174D01*
G01X-28250Y766840D02*
Y762174D01*
X-27584Y761007D01*
X-26584Y760341D01*
X-25417Y760174D01*
X-24250Y760341D01*
X-23250Y761007D01*
X-22584Y762174D01*
G01Y760174D02*
Y766840D01*
G01X-14117Y770174D02*
Y760174D01*
G01X-16450Y766840D02*
X-11784D01*
G01X-5317Y764674D02*
X16D01*
X-484Y765841D01*
X-1317Y766507D01*
X-2484Y766840D01*
X-3650Y766674D01*
X-4650Y766174D01*
X-5317Y765007D01*
X-5650Y764007D01*
Y763007D01*
X-5317Y762007D01*
X-4484Y761007D01*
X-3484Y760341D01*
X-2317Y760174D01*
X-1150Y760507D01*
X16Y761507D01*
G01X6150Y760174D02*
Y766840D01*
G01Y765507D02*
X6983Y766174D01*
X7816Y766674D01*
X8983Y766840D01*
X9816Y766674D01*
X10816Y766174D01*
G01X27416Y760174D02*
Y770174D01*
X30750D01*
X32083Y769674D01*
X33083Y769007D01*
X33916Y768007D01*
X34583Y766840D01*
X34750Y765174D01*
X34583Y763507D01*
X33916Y762341D01*
X33083Y761340D01*
X32083Y760674D01*
X30750Y760174D01*
X27416D01*
G01X42383Y766840D02*
Y760174D01*
G01Y769507D02*
X42050Y769674D01*
Y770007D01*
X42383Y770174D01*
X42716Y770007D01*
Y769674D01*
X42383Y769507D01*
G01X56683Y760174D02*
Y766840D01*
G01Y765674D02*
X56016Y766341D01*
X55016Y766674D01*
X53850Y766840D01*
X52683Y766507D01*
X51683Y765841D01*
X51016Y764841D01*
X50683Y763507D01*
X51016Y762174D01*
X51683Y761174D01*
X52683Y760507D01*
X53850Y760174D01*
X55016Y760341D01*
X56016Y760841D01*
X56683Y761507D01*
G01X59983Y760174D02*
Y766840D01*
G01Y765007D02*
X60483Y765841D01*
X61316Y766507D01*
X62483Y766840D01*
X63649Y766507D01*
X64483Y765841D01*
X64983Y765007D01*
Y760174D01*
G01Y765007D02*
X65483Y765841D01*
X66316Y766507D01*
X67483Y766840D01*
X68650Y766507D01*
X69483Y765841D01*
X69983Y764841D01*
Y760174D01*
G01X73783Y764674D02*
X79116D01*
X78616Y765841D01*
X77783Y766507D01*
X76616Y766840D01*
X75450Y766674D01*
X74450Y766174D01*
X73783Y765007D01*
X73450Y764007D01*
Y763007D01*
X73783Y762007D01*
X74616Y761007D01*
X75616Y760341D01*
X76783Y760174D01*
X77950Y760507D01*
X79116Y761507D01*
G01X87583Y770174D02*
Y760174D01*
G01X85250Y766840D02*
X89916D01*
G01X96383Y764674D02*
X101716D01*
X101216Y765841D01*
X100383Y766507D01*
X99216Y766840D01*
X98050Y766674D01*
X97050Y766174D01*
X96383Y765007D01*
X96050Y764007D01*
Y763007D01*
X96383Y762007D01*
X97216Y761007D01*
X98216Y760341D01*
X99383Y760174D01*
X100550Y760507D01*
X101716Y761507D01*
G01X107850Y760174D02*
Y766840D01*
G01Y765507D02*
X108683Y766174D01*
X109516Y766674D01*
X110683Y766840D01*
X111516Y766674D01*
X112516Y766174D01*
G01X30353Y607894D02*
X29019Y608061D01*
X27853Y608727D01*
X26853Y609727D01*
X26186Y610894D01*
X25853Y612227D01*
Y613561D01*
X26186Y614894D01*
X26853Y616061D01*
X27853Y617061D01*
X29019Y617727D01*
X30353Y617894D01*
X31686Y617727D01*
X32853Y617061D01*
X33853Y616061D01*
X34520Y614894D01*
X34853Y613561D01*
Y612227D01*
X34520Y610894D01*
X33853Y609727D01*
X32853Y608727D01*
X31686Y608061D01*
X30353Y607894D01*
G01X38820Y614560D02*
Y609894D01*
X39486Y608727D01*
X40486Y608061D01*
X41653Y607894D01*
X42820Y608061D01*
X43820Y608727D01*
X44486Y609894D01*
G01Y607894D02*
Y614560D01*
G01X52953Y617894D02*
Y607894D01*
G01X50620Y614560D02*
X55286D01*
G01X61753Y612394D02*
X67086D01*
X66586Y613561D01*
X65753Y614227D01*
X64586Y614560D01*
X63420Y614394D01*
X62420Y613894D01*
X61753Y612727D01*
X61420Y611727D01*
Y610727D01*
X61753Y609727D01*
X62586Y608727D01*
X63586Y608061D01*
X64753Y607894D01*
X65920Y608227D01*
X67086Y609227D01*
G01X73220Y607894D02*
Y614560D01*
G01Y613227D02*
X74053Y613894D01*
X74886Y614394D01*
X76053Y614560D01*
X76886Y614394D01*
X77886Y613894D01*
G01X94486Y607894D02*
Y617894D01*
X97820D01*
X99153Y617394D01*
X100153Y616727D01*
X100986Y615727D01*
X101653Y614560D01*
X101820Y612894D01*
X101653Y611227D01*
X100986Y610061D01*
X100153Y609060D01*
X99153Y608394D01*
X97820Y607894D01*
X94486D01*
G01X109453Y614560D02*
Y607894D01*
G01Y617227D02*
X109120Y617394D01*
Y617727D01*
X109453Y617894D01*
X109786Y617727D01*
Y617394D01*
X109453Y617227D01*
G01X123753Y607894D02*
Y614560D01*
G01Y613394D02*
X123086Y614061D01*
X122086Y614394D01*
X120920Y614560D01*
X119753Y614227D01*
X118753Y613561D01*
X118086Y612561D01*
X117753Y611227D01*
X118086Y609894D01*
X118753Y608894D01*
X119753Y608227D01*
X120920Y607894D01*
X122086Y608061D01*
X123086Y608561D01*
X123753Y609227D01*
G01X127053Y607894D02*
Y614560D01*
G01Y612727D02*
X127553Y613561D01*
X128386Y614227D01*
X129553Y614560D01*
X130719Y614227D01*
X131553Y613561D01*
X132053Y612727D01*
Y607894D01*
G01Y612727D02*
X132553Y613561D01*
X133386Y614227D01*
X134553Y614560D01*
X135720Y614227D01*
X136553Y613561D01*
X137053Y612561D01*
Y607894D01*
G01X140853Y612394D02*
X146186D01*
X145686Y613561D01*
X144853Y614227D01*
X143686Y614560D01*
X142520Y614394D01*
X141520Y613894D01*
X140853Y612727D01*
X140520Y611727D01*
Y610727D01*
X140853Y609727D01*
X141686Y608727D01*
X142686Y608061D01*
X143853Y607894D01*
X145020Y608227D01*
X146186Y609227D01*
G01X154653Y617894D02*
Y607894D01*
G01X152320Y614560D02*
X156986D01*
G01X163453Y612394D02*
X168786D01*
X168286Y613561D01*
X167453Y614227D01*
X166286Y614560D01*
X165120Y614394D01*
X164120Y613894D01*
X163453Y612727D01*
X163120Y611727D01*
Y610727D01*
X163453Y609727D01*
X164286Y608727D01*
X165286Y608061D01*
X166453Y607894D01*
X167620Y608227D01*
X168786Y609227D01*
G01X174920Y607894D02*
Y614560D01*
G01Y613227D02*
X175753Y613894D01*
X176586Y614394D01*
X177753Y614560D01*
X178586Y614394D01*
X179586Y613894D01*
G01X186386Y609727D02*
X190720D01*
G01Y612727D02*
X186386D01*
G01X199853Y607894D02*
Y617894D01*
X197853Y615894D01*
G01Y607894D02*
X201853D01*
G01X211153Y617894D02*
X209819Y617561D01*
X208820Y616727D01*
X208153Y615727D01*
X207653Y614394D01*
X207486Y612894D01*
X207653Y611394D01*
X208153Y610061D01*
X208820Y609060D01*
X209819Y608227D01*
X211153Y607894D01*
X212486Y608227D01*
X213486Y609060D01*
X214153Y610061D01*
X214653Y611394D01*
X214820Y612894D01*
X214653Y614394D01*
X214153Y615727D01*
X213486Y616727D01*
X212486Y617561D01*
X211153Y617894D01*
G01X218786Y609894D02*
X219786Y608727D01*
X221119Y608061D01*
X222620Y607894D01*
X223953Y608061D01*
X225286Y608894D01*
X226120Y609894D01*
X226286Y610894D01*
X225953Y612060D01*
X224786Y612894D01*
X223620Y613227D01*
X222120D01*
G01X223620D02*
X224620Y613727D01*
X225453Y614560D01*
X225786Y615561D01*
X225453Y616561D01*
X224620Y617394D01*
X223120Y617894D01*
X221620Y617727D01*
X220120Y617061D01*
G01X31353Y576894D02*
X34686D01*
Y573894D01*
X33686Y572894D01*
X32520Y572227D01*
X30853Y571894D01*
X29186Y572227D01*
X28020Y572894D01*
X27020Y573894D01*
X26353Y575061D01*
X26020Y576394D01*
Y577561D01*
X26353Y578560D01*
X27020Y579727D01*
X28020Y580727D01*
X29019Y581394D01*
X30353Y581894D01*
X31520D01*
X32853Y581561D01*
X33853Y580894D01*
G01X44653Y571894D02*
Y578560D01*
G01Y577394D02*
X43986Y578061D01*
X42986Y578394D01*
X41820Y578560D01*
X40653Y578227D01*
X39653Y577561D01*
X38986Y576561D01*
X38653Y575227D01*
X38986Y573894D01*
X39653Y572894D01*
X40653Y572227D01*
X41820Y571894D01*
X42986Y572061D01*
X43986Y572561D01*
X44653Y573227D01*
G01X49953Y568561D02*
Y578560D01*
G01Y577061D02*
X50786Y577894D01*
X51619Y578394D01*
X52953Y578560D01*
X54120Y578394D01*
X55286Y577561D01*
X55786Y576394D01*
X55953Y575227D01*
X55786Y574061D01*
X55286Y572894D01*
X54286Y572227D01*
X52953Y571894D01*
X51786Y572061D01*
X50620Y572561D01*
X49953Y573227D01*
G01X70553Y581894D02*
X72886Y571894D01*
X75553Y581894D01*
X78220Y571894D01*
X80553Y581894D01*
G01X86853Y578560D02*
Y571894D01*
G01Y581227D02*
X86520Y581394D01*
Y581727D01*
X86853Y581894D01*
X87186Y581727D01*
Y581394D01*
X86853Y581227D01*
G01X101153Y581894D02*
Y571894D01*
G01Y573394D02*
X100486Y572561D01*
X99486Y572061D01*
X98320Y571894D01*
X96986Y572227D01*
X95986Y573060D01*
X95320Y574061D01*
X95153Y575227D01*
X95320Y576394D01*
X95986Y577394D01*
X96986Y578227D01*
X98320Y578560D01*
X99486Y578394D01*
X100320Y578061D01*
X101153Y577394D01*
G01X109453Y581894D02*
Y571894D01*
G01X107120Y578560D02*
X111786D01*
G01X117920Y571894D02*
Y581894D01*
G01Y577061D02*
X118753Y577894D01*
X119586Y578394D01*
X120920Y578560D01*
X121920Y578394D01*
X123086Y577727D01*
X123586Y576727D01*
Y571894D01*
G01X129886Y573727D02*
X134220D01*
G01Y576727D02*
X129886D01*
G01X139686Y573894D02*
X140686Y572727D01*
X142019Y572061D01*
X143520Y571894D01*
X144853Y572061D01*
X146186Y572894D01*
X147020Y573894D01*
X147186Y574894D01*
X146853Y576060D01*
X145686Y576894D01*
X144520Y577227D01*
X143020D01*
G01X144520D02*
X145520Y577727D01*
X146353Y578560D01*
X146686Y579561D01*
X146353Y580561D01*
X145520Y581394D01*
X144020Y581894D01*
X142520Y581727D01*
X141020Y581061D01*
G01X154653Y581894D02*
X153319Y581561D01*
X152320Y580727D01*
X151653Y579727D01*
X151153Y578394D01*
X150986Y576894D01*
X151153Y575394D01*
X151653Y574061D01*
X152320Y573060D01*
X153319Y572227D01*
X154653Y571894D01*
X155986Y572227D01*
X156986Y573060D01*
X157653Y574061D01*
X158153Y575394D01*
X158320Y576894D01*
X158153Y578394D01*
X157653Y579727D01*
X156986Y580727D01*
X155986Y581561D01*
X154653Y581894D01*
G01X28520Y587894D02*
Y597894D01*
X36186Y587894D01*
Y597894D01*
G01X40820Y594560D02*
Y589894D01*
X41486Y588727D01*
X42486Y588061D01*
X43653Y587894D01*
X44820Y588061D01*
X45820Y588727D01*
X46486Y589894D01*
G01Y587894D02*
Y594560D01*
G01X49953Y587894D02*
Y594560D01*
G01Y592727D02*
X50453Y593561D01*
X51286Y594227D01*
X52453Y594560D01*
X53619Y594227D01*
X54453Y593561D01*
X54953Y592727D01*
Y587894D01*
G01Y592727D02*
X55453Y593561D01*
X56286Y594227D01*
X57453Y594560D01*
X58620Y594227D01*
X59453Y593561D01*
X59953Y592561D01*
Y587894D01*
G01X74053Y589227D02*
X75386Y588394D01*
X76886Y587894D01*
X78220D01*
X79553Y588394D01*
X80553Y589227D01*
X81053Y590394D01*
X80720Y591560D01*
X79886Y592561D01*
X78386Y593227D01*
X76386Y593561D01*
X75220Y594227D01*
X74720Y595394D01*
X75053Y596561D01*
X75886Y597394D01*
X77053Y597894D01*
X78220D01*
X79386Y597561D01*
X80386Y596727D01*
G01X85853Y584561D02*
Y594560D01*
G01Y593061D02*
X86686Y593894D01*
X87519Y594394D01*
X88853Y594560D01*
X90020Y594394D01*
X91186Y593561D01*
X91686Y592394D01*
X91853Y591227D01*
X91686Y590061D01*
X91186Y588894D01*
X90186Y588227D01*
X88853Y587894D01*
X87686Y588061D01*
X86520Y588561D01*
X85853Y589227D01*
G01X100153Y587894D02*
X99153Y588061D01*
X98153Y588727D01*
X97486Y589894D01*
X97153Y591227D01*
X97486Y592561D01*
X98153Y593727D01*
X99153Y594394D01*
X100153Y594560D01*
X101153Y594394D01*
X102153Y593727D01*
X102820Y592561D01*
X102986Y591227D01*
X102820Y589894D01*
X102153Y588727D01*
X101153Y588061D01*
X100153Y587894D01*
G01X108620D02*
Y597894D01*
G01X113953Y594560D02*
X108620Y590727D01*
G01X110786Y592227D02*
X114286Y587894D01*
G01X120253Y592394D02*
X125586D01*
X125086Y593561D01*
X124253Y594227D01*
X123086Y594560D01*
X121920Y594394D01*
X120920Y593894D01*
X120253Y592727D01*
X119920Y591727D01*
Y590727D01*
X120253Y589727D01*
X121086Y588727D01*
X122086Y588061D01*
X123253Y587894D01*
X124420Y588227D01*
X125586Y589227D01*
G01X131553Y589060D02*
X132386Y588394D01*
X133553Y587894D01*
X134553D01*
X135553Y588227D01*
X136220Y588727D01*
X136553Y589394D01*
X136386Y590394D01*
X135720Y590894D01*
X132719Y591894D01*
X132053Y593061D01*
X132386Y593894D01*
X133053Y594394D01*
X134053Y594560D01*
X135053Y594394D01*
X136053Y593894D01*
G01X143186Y589727D02*
X147520D01*
G01Y592727D02*
X143186D01*
G01X158653Y587894D02*
Y597894D01*
X152486Y590727D01*
X160820D01*
G01X26353Y639894D02*
X30353D01*
G01X28353D02*
Y629894D01*
G01X26353D02*
X30353D01*
G01X36820D02*
Y636560D01*
G01Y634894D02*
X37486Y635727D01*
X38486Y636394D01*
X39820Y636560D01*
X40986Y636394D01*
X41986Y635727D01*
X42486Y634561D01*
Y629894D01*
G01X48120D02*
Y636560D01*
G01Y634894D02*
X48786Y635727D01*
X49786Y636394D01*
X51120Y636560D01*
X52286Y636394D01*
X53286Y635727D01*
X53786Y634561D01*
Y629894D01*
G01X59753Y634394D02*
X65086D01*
X64586Y635561D01*
X63753Y636227D01*
X62586Y636560D01*
X61420Y636394D01*
X60420Y635894D01*
X59753Y634727D01*
X59420Y633727D01*
Y632727D01*
X59753Y631727D01*
X60586Y630727D01*
X61586Y630061D01*
X62753Y629894D01*
X63920Y630227D01*
X65086Y631227D01*
G01X71220Y629894D02*
Y636560D01*
G01Y635227D02*
X72053Y635894D01*
X72886Y636394D01*
X74053Y636560D01*
X74886Y636394D01*
X75886Y635894D01*
G01X92486Y629894D02*
Y639894D01*
X95820D01*
X97153Y639394D01*
X98153Y638727D01*
X98986Y637727D01*
X99653Y636560D01*
X99820Y634894D01*
X99653Y633227D01*
X98986Y632061D01*
X98153Y631060D01*
X97153Y630394D01*
X95820Y629894D01*
X92486D01*
G01X107453Y636560D02*
Y629894D01*
G01Y639227D02*
X107120Y639394D01*
Y639727D01*
X107453Y639894D01*
X107786Y639727D01*
Y639394D01*
X107453Y639227D01*
G01X121753Y629894D02*
Y636560D01*
G01Y635394D02*
X121086Y636061D01*
X120086Y636394D01*
X118920Y636560D01*
X117753Y636227D01*
X116753Y635561D01*
X116086Y634561D01*
X115753Y633227D01*
X116086Y631894D01*
X116753Y630894D01*
X117753Y630227D01*
X118920Y629894D01*
X120086Y630061D01*
X121086Y630561D01*
X121753Y631227D01*
G01X125053Y629894D02*
Y636560D01*
G01Y634727D02*
X125553Y635561D01*
X126386Y636227D01*
X127553Y636560D01*
X128719Y636227D01*
X129553Y635561D01*
X130053Y634727D01*
Y629894D01*
G01Y634727D02*
X130553Y635561D01*
X131386Y636227D01*
X132553Y636560D01*
X133720Y636227D01*
X134553Y635561D01*
X135053Y634561D01*
Y629894D01*
G01X138853Y634394D02*
X144186D01*
X143686Y635561D01*
X142853Y636227D01*
X141686Y636560D01*
X140520Y636394D01*
X139520Y635894D01*
X138853Y634727D01*
X138520Y633727D01*
Y632727D01*
X138853Y631727D01*
X139686Y630727D01*
X140686Y630061D01*
X141853Y629894D01*
X143020Y630227D01*
X144186Y631227D01*
G01X152653Y639894D02*
Y629894D01*
G01X150320Y636560D02*
X154986D01*
G01X161453Y634394D02*
X166786D01*
X166286Y635561D01*
X165453Y636227D01*
X164286Y636560D01*
X163120Y636394D01*
X162120Y635894D01*
X161453Y634727D01*
X161120Y633727D01*
Y632727D01*
X161453Y631727D01*
X162286Y630727D01*
X163286Y630061D01*
X164453Y629894D01*
X165620Y630227D01*
X166786Y631227D01*
G01X172920Y629894D02*
Y636560D01*
G01Y635227D02*
X173753Y635894D01*
X174586Y636394D01*
X175753Y636560D01*
X176586Y636394D01*
X177586Y635894D01*
G01X184386Y631727D02*
X188720D01*
G01Y634727D02*
X184386D01*
G01X195020Y631060D02*
X196186Y630227D01*
X197520Y629894D01*
X198853Y630227D01*
X200020Y631227D01*
X200853Y632727D01*
X201186Y634227D01*
Y636061D01*
X200853Y637561D01*
X200020Y638894D01*
X199020Y639561D01*
X197853Y639894D01*
X196519Y639561D01*
X195520Y638894D01*
X194853Y637894D01*
X194520Y636560D01*
X194853Y635394D01*
X195686Y634227D01*
X196686Y633560D01*
X197853Y633394D01*
X199186Y633727D01*
X200186Y634561D01*
X201186Y636061D01*
G01X205486Y631894D02*
X206486Y630727D01*
X207819Y630061D01*
X209320Y629894D01*
X210653Y630061D01*
X211986Y630894D01*
X212820Y631894D01*
X212986Y632894D01*
X212653Y634060D01*
X211486Y634894D01*
X210320Y635227D01*
X208820D01*
G01X210320D02*
X211320Y635727D01*
X212153Y636560D01*
X212486Y637561D01*
X212153Y638561D01*
X211320Y639394D01*
X209820Y639894D01*
X208320Y639727D01*
X206820Y639061D01*
G54D12*
G01X338786Y85994D02*
Y93994D01*
X341320D01*
G01X340386Y90127D02*
X338786D01*
G01X344053Y85994D02*
X343653Y86127D01*
X343253Y86661D01*
X342986Y87594D01*
X342853Y88661D01*
X342986Y89727D01*
X343253Y90661D01*
X343653Y91194D01*
X344053Y91327D01*
X344453Y91194D01*
X344853Y90661D01*
X345120Y89727D01*
X345186Y88661D01*
X345120Y87594D01*
X344853Y86661D01*
X344453Y86127D01*
X344053Y85994D01*
G01X347120D02*
Y91327D01*
G01Y90261D02*
X347453Y90794D01*
X347786Y91194D01*
X348253Y91327D01*
X348586Y91194D01*
X348986Y90794D01*
G01X355053Y89594D02*
X357186D01*
X356986Y90527D01*
X356653Y91061D01*
X356186Y91327D01*
X355720Y91194D01*
X355320Y90794D01*
X355053Y89861D01*
X354920Y89060D01*
Y88261D01*
X355053Y87461D01*
X355386Y86661D01*
X355786Y86127D01*
X356253Y85994D01*
X356720Y86261D01*
X357186Y87060D01*
G01X359053Y91327D02*
X361053Y85994D01*
G01Y91327D02*
X359053Y85994D01*
G01X365253D02*
Y91327D01*
G01Y90394D02*
X364986Y90927D01*
X364586Y91194D01*
X364120Y91327D01*
X363653Y91061D01*
X363253Y90527D01*
X362986Y89727D01*
X362853Y88661D01*
X362986Y87594D01*
X363253Y86794D01*
X363653Y86261D01*
X364120Y85994D01*
X364586Y86127D01*
X364986Y86527D01*
X365253Y87060D01*
G01X366053Y85994D02*
Y91327D01*
G01Y89861D02*
X366253Y90527D01*
X366586Y91061D01*
X367053Y91327D01*
X367520Y91061D01*
X367853Y90527D01*
X368053Y89861D01*
Y85994D01*
G01Y89861D02*
X368253Y90527D01*
X368586Y91061D01*
X369053Y91327D01*
X369520Y91061D01*
X369853Y90527D01*
X370053Y89727D01*
Y85994D01*
G01X370853Y83327D02*
Y91327D01*
G01Y90127D02*
X371186Y90794D01*
X371520Y91194D01*
X372053Y91327D01*
X372520Y91194D01*
X372986Y90527D01*
X373186Y89594D01*
X373253Y88661D01*
X373186Y87727D01*
X372986Y86794D01*
X372586Y86261D01*
X372053Y85994D01*
X371586Y86127D01*
X371120Y86527D01*
X370853Y87060D01*
G01X376053Y85994D02*
Y93994D01*
G01X379053Y89594D02*
X381186D01*
X380986Y90527D01*
X380653Y91061D01*
X380186Y91327D01*
X379720Y91194D01*
X379320Y90794D01*
X379053Y89861D01*
X378920Y89060D01*
Y88261D01*
X379053Y87461D01*
X379386Y86661D01*
X379786Y86127D01*
X380253Y85994D01*
X380720Y86261D01*
X381186Y87060D01*
G01X384053Y85727D02*
X383920Y85861D01*
Y86127D01*
X384053Y86261D01*
X384186Y86127D01*
Y85861D01*
X384053Y85727D01*
G01Y89327D02*
X383920Y89461D01*
Y89727D01*
X384053Y89861D01*
X384186Y89727D01*
Y89461D01*
X384053Y89327D01*
G01X390653Y85994D02*
Y93994D01*
G01X393453D02*
Y85994D01*
G01Y89994D02*
X390653D01*
G01X396053Y85994D02*
X395653Y86127D01*
X395253Y86661D01*
X394986Y87594D01*
X394853Y88661D01*
X394986Y89727D01*
X395253Y90661D01*
X395653Y91194D01*
X396053Y91327D01*
X396453Y91194D01*
X396853Y90661D01*
X397120Y89727D01*
X397186Y88661D01*
X397120Y87594D01*
X396853Y86661D01*
X396453Y86127D01*
X396053Y85994D01*
G01X400053D02*
Y93994D01*
G01X403053Y89594D02*
X405186D01*
X404986Y90527D01*
X404653Y91061D01*
X404186Y91327D01*
X403720Y91194D01*
X403320Y90794D01*
X403053Y89861D01*
X402920Y89060D01*
Y88261D01*
X403053Y87461D01*
X403386Y86661D01*
X403786Y86127D01*
X404253Y85994D01*
X404720Y86261D01*
X405186Y87060D01*
G01X410586Y85994D02*
Y93994D01*
X411920D01*
X412453Y93594D01*
X412853Y93061D01*
X413186Y92261D01*
X413453Y91327D01*
X413520Y89994D01*
X413453Y88661D01*
X413186Y87727D01*
X412853Y86927D01*
X412453Y86394D01*
X411920Y85994D01*
X410586D01*
G01X416053Y91327D02*
Y85994D01*
G01Y93461D02*
X415920Y93594D01*
Y93861D01*
X416053Y93994D01*
X416186Y93861D01*
Y93594D01*
X416053Y93461D01*
G01X421253Y85994D02*
Y91327D01*
G01Y90394D02*
X420986Y90927D01*
X420586Y91194D01*
X420120Y91327D01*
X419653Y91061D01*
X419253Y90527D01*
X418986Y89727D01*
X418853Y88661D01*
X418986Y87594D01*
X419253Y86794D01*
X419653Y86261D01*
X420120Y85994D01*
X420586Y86127D01*
X420986Y86527D01*
X421253Y87060D01*
G01X424053Y85727D02*
X423920Y85861D01*
Y86127D01*
X424053Y86261D01*
X424186Y86127D01*
Y85861D01*
X424053Y85727D01*
G01X426586Y87594D02*
X426986Y86661D01*
X427520Y86127D01*
X428120Y85994D01*
X428653Y86127D01*
X429186Y86794D01*
X429520Y87594D01*
X429586Y88394D01*
X429453Y89327D01*
X428986Y89994D01*
X428520Y90261D01*
X427920D01*
G01X428520D02*
X428920Y90661D01*
X429253Y91327D01*
X429386Y92127D01*
X429253Y92927D01*
X428920Y93594D01*
X428320Y93994D01*
X427720Y93861D01*
X427120Y93327D01*
G01X432053Y85727D02*
X431920Y85861D01*
Y86127D01*
X432053Y86261D01*
X432186Y86127D01*
Y85861D01*
X432053Y85727D01*
G01X436053Y85994D02*
Y93994D01*
X435253Y92394D01*
G01Y85994D02*
X436853D01*
G01X440053D02*
X440520Y86127D01*
X441053Y86527D01*
X441386Y87194D01*
X441520Y88127D01*
X441386Y89060D01*
X440986Y89861D01*
X440386Y90261D01*
X439720D01*
X439320Y90527D01*
X438986Y91194D01*
X438853Y92127D01*
X439053Y93061D01*
X439520Y93727D01*
X440053Y93994D01*
X440586Y93727D01*
X441053Y93061D01*
X441253Y92127D01*
X441120Y91194D01*
X440786Y90527D01*
X440386Y90261D01*
X439720D01*
X439120Y89861D01*
X438720Y89060D01*
X438586Y88127D01*
X438720Y87194D01*
X439053Y86527D01*
X439586Y86127D01*
X440053Y85994D01*
G01X442053D02*
Y91327D01*
G01Y89861D02*
X442253Y90527D01*
X442586Y91061D01*
X443053Y91327D01*
X443520Y91061D01*
X443853Y90527D01*
X444053Y89861D01*
Y85994D01*
G01Y89861D02*
X444253Y90527D01*
X444586Y91061D01*
X445053Y91327D01*
X445520Y91061D01*
X445853Y90527D01*
X446053Y89727D01*
Y85994D01*
G01D02*
Y91327D01*
G01Y89861D02*
X446253Y90527D01*
X446586Y91061D01*
X447053Y91327D01*
X447520Y91061D01*
X447853Y90527D01*
X448053Y89861D01*
Y85994D01*
G01Y89861D02*
X448253Y90527D01*
X448586Y91061D01*
X449053Y91327D01*
X449520Y91061D01*
X449853Y90527D01*
X450053Y89727D01*
Y85994D01*
G01X456053Y91327D02*
Y85994D01*
G01Y93461D02*
X455920Y93594D01*
Y93861D01*
X456053Y93994D01*
X456186Y93861D01*
Y93594D01*
X456053Y93461D01*
G01X459053Y86927D02*
X459386Y86394D01*
X459853Y85994D01*
X460253D01*
X460653Y86261D01*
X460920Y86661D01*
X461053Y87194D01*
X460986Y87994D01*
X460720Y88394D01*
X459520Y89194D01*
X459253Y90127D01*
X459386Y90794D01*
X459653Y91194D01*
X460053Y91327D01*
X460453Y91194D01*
X460853Y90794D01*
G01X466053Y85994D02*
Y91327D01*
G01Y89861D02*
X466253Y90527D01*
X466586Y91061D01*
X467053Y91327D01*
X467520Y91061D01*
X467853Y90527D01*
X468053Y89861D01*
Y85994D01*
G01Y89861D02*
X468253Y90527D01*
X468586Y91061D01*
X469053Y91327D01*
X469520Y91061D01*
X469853Y90527D01*
X470053Y89727D01*
Y85994D01*
G01X473253D02*
Y91327D01*
G01Y90394D02*
X472986Y90927D01*
X472586Y91194D01*
X472120Y91327D01*
X471653Y91061D01*
X471253Y90527D01*
X470986Y89727D01*
X470853Y88661D01*
X470986Y87594D01*
X471253Y86794D01*
X471653Y86261D01*
X472120Y85994D01*
X472586Y86127D01*
X472986Y86527D01*
X473253Y87060D01*
G01X475120Y85994D02*
Y91327D01*
G01Y90261D02*
X475453Y90794D01*
X475786Y91194D01*
X476253Y91327D01*
X476586Y91194D01*
X476986Y90794D01*
G01X478920Y85994D02*
Y93994D01*
G01X481053Y91327D02*
X478920Y88261D01*
G01X479786Y89461D02*
X481186Y85994D01*
G01X483053Y89594D02*
X485186D01*
X484986Y90527D01*
X484653Y91061D01*
X484186Y91327D01*
X483720Y91194D01*
X483320Y90794D01*
X483053Y89861D01*
X482920Y89060D01*
Y88261D01*
X483053Y87461D01*
X483386Y86661D01*
X483786Y86127D01*
X484253Y85994D01*
X484720Y86261D01*
X485186Y87060D01*
G01X489253Y93994D02*
Y85994D01*
G01Y87194D02*
X488986Y86527D01*
X488586Y86127D01*
X488120Y85994D01*
X487586Y86261D01*
X487186Y86927D01*
X486920Y87727D01*
X486853Y88661D01*
X486920Y89594D01*
X487186Y90394D01*
X487586Y91061D01*
X488120Y91327D01*
X488586Y91194D01*
X488920Y90927D01*
X489253Y90394D01*
G01X496053Y91327D02*
Y85994D01*
G01Y93461D02*
X495920Y93594D01*
Y93861D01*
X496053Y93994D01*
X496186Y93861D01*
Y93594D01*
X496053Y93461D01*
G01X498920Y85994D02*
Y91327D01*
G01Y89994D02*
X499186Y90661D01*
X499586Y91194D01*
X500120Y91327D01*
X500586Y91194D01*
X500986Y90661D01*
X501186Y89727D01*
Y85994D01*
G01X506053D02*
Y91327D01*
G01Y89861D02*
X506253Y90527D01*
X506586Y91061D01*
X507053Y91327D01*
X507520Y91061D01*
X507853Y90527D01*
X508053Y89861D01*
Y85994D01*
G01Y89861D02*
X508253Y90527D01*
X508586Y91061D01*
X509053Y91327D01*
X509520Y91061D01*
X509853Y90527D01*
X510053Y89727D01*
Y85994D01*
G01X511053Y89594D02*
X513186D01*
X512986Y90527D01*
X512653Y91061D01*
X512186Y91327D01*
X511720Y91194D01*
X511320Y90794D01*
X511053Y89861D01*
X510920Y89060D01*
Y88261D01*
X511053Y87461D01*
X511386Y86661D01*
X511786Y86127D01*
X512253Y85994D01*
X512720Y86261D01*
X513186Y87060D01*
G01X517120Y90661D02*
X516653Y91194D01*
X516253Y91327D01*
X515720Y91061D01*
X515320Y90527D01*
X515053Y89594D01*
X514986Y88661D01*
X515053Y87727D01*
X515320Y86927D01*
X515720Y86261D01*
X516253Y85994D01*
X516720Y86261D01*
X517120Y86794D01*
G01X518920Y85994D02*
Y93994D01*
G01Y90127D02*
X519253Y90794D01*
X519586Y91194D01*
X520120Y91327D01*
X520520Y91194D01*
X520986Y90661D01*
X521186Y89861D01*
Y85994D01*
G01X525253D02*
Y91327D01*
G01Y90394D02*
X524986Y90927D01*
X524586Y91194D01*
X524120Y91327D01*
X523653Y91061D01*
X523253Y90527D01*
X522986Y89727D01*
X522853Y88661D01*
X522986Y87594D01*
X523253Y86794D01*
X523653Y86261D01*
X524120Y85994D01*
X524586Y86127D01*
X524986Y86527D01*
X525253Y87060D01*
G01X526920Y85994D02*
Y91327D01*
G01Y89994D02*
X527186Y90661D01*
X527586Y91194D01*
X528120Y91327D01*
X528586Y91194D01*
X528986Y90661D01*
X529186Y89727D01*
Y85994D01*
G01X532053Y91327D02*
Y85994D01*
G01Y93461D02*
X531920Y93594D01*
Y93861D01*
X532053Y93994D01*
X532186Y93861D01*
Y93594D01*
X532053Y93461D01*
G01X537120Y90661D02*
X536653Y91194D01*
X536253Y91327D01*
X535720Y91061D01*
X535320Y90527D01*
X535053Y89594D01*
X534986Y88661D01*
X535053Y87727D01*
X535320Y86927D01*
X535720Y86261D01*
X536253Y85994D01*
X536720Y86261D01*
X537120Y86794D01*
G01X541253Y85994D02*
Y91327D01*
G01Y90394D02*
X540986Y90927D01*
X540586Y91194D01*
X540120Y91327D01*
X539653Y91061D01*
X539253Y90527D01*
X538986Y89727D01*
X538853Y88661D01*
X538986Y87594D01*
X539253Y86794D01*
X539653Y86261D01*
X540120Y85994D01*
X540586Y86127D01*
X540986Y86527D01*
X541253Y87060D01*
G01X544053Y85994D02*
Y93994D01*
G01X553253D02*
Y85994D01*
G01Y87194D02*
X552986Y86527D01*
X552586Y86127D01*
X552120Y85994D01*
X551586Y86261D01*
X551186Y86927D01*
X550920Y87727D01*
X550853Y88661D01*
X550920Y89594D01*
X551186Y90394D01*
X551586Y91061D01*
X552120Y91327D01*
X552586Y91194D01*
X552920Y90927D01*
X553253Y90394D01*
G01X555120Y85994D02*
Y91327D01*
G01Y90261D02*
X555453Y90794D01*
X555786Y91194D01*
X556253Y91327D01*
X556586Y91194D01*
X556986Y90794D01*
G01X561253Y85994D02*
Y91327D01*
G01Y90394D02*
X560986Y90927D01*
X560586Y91194D01*
X560120Y91327D01*
X559653Y91061D01*
X559253Y90527D01*
X558986Y89727D01*
X558853Y88661D01*
X558986Y87594D01*
X559253Y86794D01*
X559653Y86261D01*
X560120Y85994D01*
X560586Y86127D01*
X560986Y86527D01*
X561253Y87060D01*
G01X562386Y91327D02*
X563186Y85994D01*
X564053Y91327D01*
X564920Y85994D01*
X565720Y91327D01*
G01X568053D02*
Y85994D01*
G01Y93461D02*
X567920Y93594D01*
Y93861D01*
X568053Y93994D01*
X568186Y93861D01*
Y93594D01*
X568053Y93461D01*
G01X570920Y85994D02*
Y91327D01*
G01Y89994D02*
X571186Y90661D01*
X571586Y91194D01*
X572120Y91327D01*
X572586Y91194D01*
X572986Y90661D01*
X573186Y89727D01*
Y85994D01*
G01X575120Y83994D02*
X575586Y83461D01*
X576120Y83327D01*
X576586Y83461D01*
X576986Y84127D01*
X577253Y85061D01*
Y91327D01*
G01Y90261D02*
X576986Y90794D01*
X576586Y91194D01*
X576120Y91327D01*
X575586Y91061D01*
X575253Y90527D01*
X574986Y89594D01*
X574853Y88661D01*
X574920Y87861D01*
X575186Y86927D01*
X575586Y86261D01*
X576120Y85994D01*
X576520Y86127D01*
X576986Y86661D01*
X577253Y87194D01*
G01X585253Y85994D02*
Y91327D01*
G01Y90394D02*
X584986Y90927D01*
X584586Y91194D01*
X584120Y91327D01*
X583653Y91061D01*
X583253Y90527D01*
X582986Y89727D01*
X582853Y88661D01*
X582986Y87594D01*
X583253Y86794D01*
X583653Y86261D01*
X584120Y85994D01*
X584586Y86127D01*
X584986Y86527D01*
X585253Y87060D01*
G01X586920Y85994D02*
Y91327D01*
G01Y89994D02*
X587186Y90661D01*
X587586Y91194D01*
X588120Y91327D01*
X588586Y91194D01*
X588986Y90661D01*
X589186Y89727D01*
Y85994D01*
G01X593253Y93994D02*
Y85994D01*
G01Y87194D02*
X592986Y86527D01*
X592586Y86127D01*
X592120Y85994D01*
X591586Y86261D01*
X591186Y86927D01*
X590920Y87727D01*
X590853Y88661D01*
X590920Y89594D01*
X591186Y90394D01*
X591586Y91061D01*
X592120Y91327D01*
X592586Y91194D01*
X592920Y90927D01*
X593253Y90394D01*
G01X598920Y85994D02*
Y93994D01*
G01Y90127D02*
X599253Y90794D01*
X599586Y91194D01*
X600120Y91327D01*
X600520Y91194D01*
X600986Y90661D01*
X601186Y89861D01*
Y85994D01*
G01X604053D02*
X603653Y86127D01*
X603253Y86661D01*
X602986Y87594D01*
X602853Y88661D01*
X602986Y89727D01*
X603253Y90661D01*
X603653Y91194D01*
X604053Y91327D01*
X604453Y91194D01*
X604853Y90661D01*
X605120Y89727D01*
X605186Y88661D01*
X605120Y87594D01*
X604853Y86661D01*
X604453Y86127D01*
X604053Y85994D01*
G01X608053D02*
Y93994D01*
G01X611053Y89594D02*
X613186D01*
X612986Y90527D01*
X612653Y91061D01*
X612186Y91327D01*
X611720Y91194D01*
X611320Y90794D01*
X611053Y89861D01*
X610920Y89060D01*
Y88261D01*
X611053Y87461D01*
X611386Y86661D01*
X611786Y86127D01*
X612253Y85994D01*
X612720Y86261D01*
X613186Y87060D01*
G01X618586Y85994D02*
Y93994D01*
X619920D01*
X620453Y93594D01*
X620853Y93061D01*
X621186Y92261D01*
X621453Y91327D01*
X621520Y89994D01*
X621453Y88661D01*
X621186Y87727D01*
X620853Y86927D01*
X620453Y86394D01*
X619920Y85994D01*
X618586D01*
G01X624053Y91327D02*
Y85994D01*
G01Y93461D02*
X623920Y93594D01*
Y93861D01*
X624053Y93994D01*
X624186Y93861D01*
Y93594D01*
X624053Y93461D01*
G01X629253Y85994D02*
Y91327D01*
G01Y90394D02*
X628986Y90927D01*
X628586Y91194D01*
X628120Y91327D01*
X627653Y91061D01*
X627253Y90527D01*
X626986Y89727D01*
X626853Y88661D01*
X626986Y87594D01*
X627253Y86794D01*
X627653Y86261D01*
X628120Y85994D01*
X628586Y86127D01*
X628986Y86527D01*
X629253Y87060D01*
G01X632053Y85727D02*
X631920Y85861D01*
Y86127D01*
X632053Y86261D01*
X632186Y86127D01*
Y85861D01*
X632053Y85727D01*
G01X640053Y85994D02*
Y93994D01*
X639253Y92394D01*
G01Y85994D02*
X640853D01*
G01X642786Y92661D02*
X643186Y93461D01*
X643653Y93861D01*
X644186Y93994D01*
X644853Y93727D01*
X645320Y93061D01*
X645453Y92261D01*
X645386Y91460D01*
X645120Y90794D01*
X643786Y89461D01*
X643186Y88527D01*
X642786Y87194D01*
X642653Y85994D01*
X645453D01*
G01X646786Y89327D02*
X647253Y90261D01*
X647653Y90794D01*
X648186Y91061D01*
X648653Y90794D01*
X648986Y90261D01*
X649253Y89461D01*
X649320Y88527D01*
X649253Y87727D01*
X648986Y86927D01*
X648586Y86261D01*
X648120Y85994D01*
X647586Y86261D01*
X647120Y87060D01*
X646853Y88261D01*
X646786Y89594D01*
X646920Y91327D01*
X647120Y92261D01*
X647453Y93194D01*
X647920Y93861D01*
X648386Y93994D01*
X648853Y93727D01*
X649186Y93061D01*
G01X650053Y85994D02*
Y91327D01*
G01Y89861D02*
X650253Y90527D01*
X650586Y91061D01*
X651053Y91327D01*
X651520Y91061D01*
X651853Y90527D01*
X652053Y89861D01*
Y85994D01*
G01Y89861D02*
X652253Y90527D01*
X652586Y91061D01*
X653053Y91327D01*
X653520Y91061D01*
X653853Y90527D01*
X654053Y89727D01*
Y85994D01*
G01X656053Y91327D02*
Y85994D01*
G01Y93461D02*
X655920Y93594D01*
Y93861D01*
X656053Y93994D01*
X656186Y93861D01*
Y93594D01*
X656053Y93461D01*
G01X660053Y85994D02*
Y93994D01*
G01X668053Y91327D02*
Y85994D01*
G01Y93461D02*
X667920Y93594D01*
Y93861D01*
X668053Y93994D01*
X668186Y93861D01*
Y93594D01*
X668053Y93461D01*
G01X671053Y86927D02*
X671386Y86394D01*
X671853Y85994D01*
X672253D01*
X672653Y86261D01*
X672920Y86661D01*
X673053Y87194D01*
X672986Y87994D01*
X672720Y88394D01*
X671520Y89194D01*
X671253Y90127D01*
X671386Y90794D01*
X671653Y91194D01*
X672053Y91327D01*
X672453Y91194D01*
X672853Y90794D01*
G01X678053Y85994D02*
Y91327D01*
G01Y89861D02*
X678253Y90527D01*
X678586Y91061D01*
X679053Y91327D01*
X679520Y91061D01*
X679853Y90527D01*
X680053Y89861D01*
Y85994D01*
G01Y89861D02*
X680253Y90527D01*
X680586Y91061D01*
X681053Y91327D01*
X681520Y91061D01*
X681853Y90527D01*
X682053Y89727D01*
Y85994D01*
G01X685253D02*
Y91327D01*
G01Y90394D02*
X684986Y90927D01*
X684586Y91194D01*
X684120Y91327D01*
X683653Y91061D01*
X683253Y90527D01*
X682986Y89727D01*
X682853Y88661D01*
X682986Y87594D01*
X683253Y86794D01*
X683653Y86261D01*
X684120Y85994D01*
X684586Y86127D01*
X684986Y86527D01*
X685253Y87060D01*
G01X687120Y85994D02*
Y91327D01*
G01Y90261D02*
X687453Y90794D01*
X687786Y91194D01*
X688253Y91327D01*
X688586Y91194D01*
X688986Y90794D01*
G01X690920Y85994D02*
Y93994D01*
G01X693053Y91327D02*
X690920Y88261D01*
G01X691786Y89461D02*
X693186Y85994D01*
G01X695053Y89594D02*
X697186D01*
X696986Y90527D01*
X696653Y91061D01*
X696186Y91327D01*
X695720Y91194D01*
X695320Y90794D01*
X695053Y89861D01*
X694920Y89060D01*
Y88261D01*
X695053Y87461D01*
X695386Y86661D01*
X695786Y86127D01*
X696253Y85994D01*
X696720Y86261D01*
X697186Y87060D01*
G01X701253Y93994D02*
Y85994D01*
G01Y87194D02*
X700986Y86527D01*
X700586Y86127D01*
X700120Y85994D01*
X699586Y86261D01*
X699186Y86927D01*
X698920Y87727D01*
X698853Y88661D01*
X698920Y89594D01*
X699186Y90394D01*
X699586Y91061D01*
X700120Y91327D01*
X700586Y91194D01*
X700920Y90927D01*
X701253Y90394D01*
G01X708053Y91327D02*
Y85994D01*
G01Y93461D02*
X707920Y93594D01*
Y93861D01*
X708053Y93994D01*
X708186Y93861D01*
Y93594D01*
X708053Y93461D01*
G01X710920Y85994D02*
Y91327D01*
G01Y89994D02*
X711186Y90661D01*
X711586Y91194D01*
X712120Y91327D01*
X712586Y91194D01*
X712986Y90661D01*
X713186Y89727D01*
Y85994D01*
G01X720453Y89994D02*
X721786D01*
Y87594D01*
X721386Y86794D01*
X720920Y86261D01*
X720253Y85994D01*
X719586Y86261D01*
X719120Y86794D01*
X718720Y87594D01*
X718453Y88527D01*
X718320Y89594D01*
Y90527D01*
X718453Y91327D01*
X718720Y92261D01*
X719120Y93061D01*
X719520Y93594D01*
X720053Y93994D01*
X720520D01*
X721053Y93727D01*
X721453Y93194D01*
G01X723053Y89594D02*
X725186D01*
X724986Y90527D01*
X724653Y91061D01*
X724186Y91327D01*
X723720Y91194D01*
X723320Y90794D01*
X723053Y89861D01*
X722920Y89060D01*
Y88261D01*
X723053Y87461D01*
X723386Y86661D01*
X723786Y86127D01*
X724253Y85994D01*
X724720Y86261D01*
X725186Y87060D01*
G01X727120Y85994D02*
Y91327D01*
G01Y90261D02*
X727453Y90794D01*
X727786Y91194D01*
X728253Y91327D01*
X728586Y91194D01*
X728986Y90794D01*
G01X730853Y85994D02*
Y93994D01*
G01Y89994D02*
X731186Y90794D01*
X731586Y91194D01*
X731986Y91327D01*
X732586Y91061D01*
X732986Y90527D01*
X733253Y89594D01*
Y88527D01*
X733120Y87461D01*
X732853Y86661D01*
X732386Y86127D01*
X731986Y85994D01*
X731586Y86127D01*
X731186Y86527D01*
X730853Y87194D01*
G01X735053Y89594D02*
X737186D01*
X736986Y90527D01*
X736653Y91061D01*
X736186Y91327D01*
X735720Y91194D01*
X735320Y90794D01*
X735053Y89861D01*
X734920Y89060D01*
Y88261D01*
X735053Y87461D01*
X735386Y86661D01*
X735786Y86127D01*
X736253Y85994D01*
X736720Y86261D01*
X737186Y87060D01*
G01X739120Y85994D02*
Y91327D01*
G01Y90261D02*
X739453Y90794D01*
X739786Y91194D01*
X740253Y91327D01*
X740586Y91194D01*
X740986Y90794D01*
G01X747653Y85994D02*
Y92794D01*
X747786Y93461D01*
X748053Y93861D01*
X748453Y93994D01*
X748853Y93727D01*
X749053Y93061D01*
G01X748253Y90794D02*
X746920D01*
G01X752053Y91327D02*
Y85994D01*
G01Y93461D02*
X751920Y93594D01*
Y93861D01*
X752053Y93994D01*
X752186Y93861D01*
Y93594D01*
X752053Y93461D01*
G01X756053Y85994D02*
Y93994D01*
G01X759053Y89594D02*
X761186D01*
X760986Y90527D01*
X760653Y91061D01*
X760186Y91327D01*
X759720Y91194D01*
X759320Y90794D01*
X759053Y89861D01*
X758920Y89060D01*
Y88261D01*
X759053Y87461D01*
X759386Y86661D01*
X759786Y86127D01*
X760253Y85994D01*
X760720Y86261D01*
X761186Y87060D01*
G01X764053Y85727D02*
X763920Y85861D01*
Y86127D01*
X764053Y86261D01*
X764186Y86127D01*
Y85861D01*
X764053Y85727D01*
G01X338886Y118094D02*
Y112361D01*
X339153Y111160D01*
X339686Y110361D01*
X340353Y110094D01*
X341020Y110361D01*
X341553Y111160D01*
X341820Y112361D01*
Y118094D01*
G01X343220Y110094D02*
Y115427D01*
G01Y114094D02*
X343486Y114761D01*
X343886Y115294D01*
X344420Y115427D01*
X344886Y115294D01*
X345286Y114761D01*
X345486Y113827D01*
Y110094D01*
G01X348353Y115427D02*
Y110094D01*
G01Y117561D02*
X348220Y117694D01*
Y117961D01*
X348353Y118094D01*
X348486Y117961D01*
Y117694D01*
X348353Y117561D01*
G01X352353Y118094D02*
Y110094D01*
G01X351420Y115427D02*
X353286D01*
G01X361420Y114761D02*
X360953Y115294D01*
X360553Y115427D01*
X360020Y115161D01*
X359620Y114627D01*
X359353Y113694D01*
X359286Y112761D01*
X359353Y111827D01*
X359620Y111027D01*
X360020Y110361D01*
X360553Y110094D01*
X361020Y110361D01*
X361420Y110894D01*
G01X364353Y110094D02*
X363953Y110227D01*
X363553Y110761D01*
X363286Y111694D01*
X363153Y112761D01*
X363286Y113827D01*
X363553Y114761D01*
X363953Y115294D01*
X364353Y115427D01*
X364753Y115294D01*
X365153Y114761D01*
X365420Y113827D01*
X365486Y112761D01*
X365420Y111694D01*
X365153Y110761D01*
X364753Y110227D01*
X364353Y110094D01*
G01X367220D02*
Y115427D01*
G01Y114094D02*
X367486Y114761D01*
X367886Y115294D01*
X368420Y115427D01*
X368886Y115294D01*
X369286Y114761D01*
X369486Y113827D01*
Y110094D01*
G01X371153Y115427D02*
X372353Y110094D01*
X373553Y115427D01*
G01X375353Y113694D02*
X377486D01*
X377286Y114627D01*
X376953Y115161D01*
X376486Y115427D01*
X376020Y115294D01*
X375620Y114894D01*
X375353Y113961D01*
X375220Y113160D01*
Y112361D01*
X375353Y111561D01*
X375686Y110761D01*
X376086Y110227D01*
X376553Y110094D01*
X377020Y110361D01*
X377486Y111160D01*
G01X379420Y110094D02*
Y115427D01*
G01Y114361D02*
X379753Y114894D01*
X380086Y115294D01*
X380553Y115427D01*
X380886Y115294D01*
X381286Y114894D01*
G01X383353Y111027D02*
X383686Y110494D01*
X384153Y110094D01*
X384553D01*
X384953Y110361D01*
X385220Y110761D01*
X385353Y111294D01*
X385286Y112094D01*
X385020Y112494D01*
X383820Y113294D01*
X383553Y114227D01*
X383686Y114894D01*
X383953Y115294D01*
X384353Y115427D01*
X384753Y115294D01*
X385153Y114894D01*
G01X388353Y115427D02*
Y110094D01*
G01Y117561D02*
X388220Y117694D01*
Y117961D01*
X388353Y118094D01*
X388486Y117961D01*
Y117694D01*
X388353Y117561D01*
G01X392353Y110094D02*
X391953Y110227D01*
X391553Y110761D01*
X391286Y111694D01*
X391153Y112761D01*
X391286Y113827D01*
X391553Y114761D01*
X391953Y115294D01*
X392353Y115427D01*
X392753Y115294D01*
X393153Y114761D01*
X393420Y113827D01*
X393486Y112761D01*
X393420Y111694D01*
X393153Y110761D01*
X392753Y110227D01*
X392353Y110094D01*
G01X395220D02*
Y115427D01*
G01Y114094D02*
X395486Y114761D01*
X395886Y115294D01*
X396420Y115427D01*
X396886Y115294D01*
X397286Y114761D01*
X397486Y113827D01*
Y110094D01*
G01X403353Y113694D02*
X405486D01*
X405286Y114627D01*
X404953Y115161D01*
X404486Y115427D01*
X404020Y115294D01*
X403620Y114894D01*
X403353Y113961D01*
X403220Y113160D01*
Y112361D01*
X403353Y111561D01*
X403686Y110761D01*
X404086Y110227D01*
X404553Y110094D01*
X405020Y110361D01*
X405486Y111160D01*
G01X407420Y110094D02*
Y115427D01*
G01Y114361D02*
X407753Y114894D01*
X408086Y115294D01*
X408553Y115427D01*
X408886Y115294D01*
X409286Y114894D01*
G01X411420Y110094D02*
Y115427D01*
G01Y114361D02*
X411753Y114894D01*
X412086Y115294D01*
X412553Y115427D01*
X412886Y115294D01*
X413286Y114894D01*
G01X416353Y110094D02*
X415953Y110227D01*
X415553Y110761D01*
X415286Y111694D01*
X415153Y112761D01*
X415286Y113827D01*
X415553Y114761D01*
X415953Y115294D01*
X416353Y115427D01*
X416753Y115294D01*
X417153Y114761D01*
X417420Y113827D01*
X417486Y112761D01*
X417420Y111694D01*
X417153Y110761D01*
X416753Y110227D01*
X416353Y110094D01*
G01X419420D02*
Y115427D01*
G01Y114361D02*
X419753Y114894D01*
X420086Y115294D01*
X420553Y115427D01*
X420886Y115294D01*
X421286Y114894D01*
G01X427153Y110094D02*
Y118094D01*
G01Y114094D02*
X427486Y114894D01*
X427886Y115294D01*
X428286Y115427D01*
X428886Y115161D01*
X429286Y114627D01*
X429553Y113694D01*
Y112627D01*
X429420Y111561D01*
X429153Y110761D01*
X428686Y110227D01*
X428286Y110094D01*
X427886Y110227D01*
X427486Y110627D01*
X427153Y111294D01*
G01X431353Y113694D02*
X433486D01*
X433286Y114627D01*
X432953Y115161D01*
X432486Y115427D01*
X432020Y115294D01*
X431620Y114894D01*
X431353Y113961D01*
X431220Y113160D01*
Y112361D01*
X431353Y111561D01*
X431686Y110761D01*
X432086Y110227D01*
X432553Y110094D01*
X433020Y110361D01*
X433486Y111160D01*
G01X436353Y118094D02*
Y110094D01*
G01X435420Y115427D02*
X437286D01*
G01X438686D02*
X439486Y110094D01*
X440353Y115427D01*
X441220Y110094D01*
X442020Y115427D01*
G01X443353Y113694D02*
X445486D01*
X445286Y114627D01*
X444953Y115161D01*
X444486Y115427D01*
X444020Y115294D01*
X443620Y114894D01*
X443353Y113961D01*
X443220Y113160D01*
Y112361D01*
X443353Y111561D01*
X443686Y110761D01*
X444086Y110227D01*
X444553Y110094D01*
X445020Y110361D01*
X445486Y111160D01*
G01X447353Y113694D02*
X449486D01*
X449286Y114627D01*
X448953Y115161D01*
X448486Y115427D01*
X448020Y115294D01*
X447620Y114894D01*
X447353Y113961D01*
X447220Y113160D01*
Y112361D01*
X447353Y111561D01*
X447686Y110761D01*
X448086Y110227D01*
X448553Y110094D01*
X449020Y110361D01*
X449486Y111160D01*
G01X451220Y110094D02*
Y115427D01*
G01Y114094D02*
X451486Y114761D01*
X451886Y115294D01*
X452420Y115427D01*
X452886Y115294D01*
X453286Y114761D01*
X453486Y113827D01*
Y110094D01*
G01X458353D02*
Y115427D01*
G01Y113961D02*
X458553Y114627D01*
X458886Y115161D01*
X459353Y115427D01*
X459820Y115161D01*
X460153Y114627D01*
X460353Y113961D01*
Y110094D01*
G01Y113961D02*
X460553Y114627D01*
X460886Y115161D01*
X461353Y115427D01*
X461820Y115161D01*
X462153Y114627D01*
X462353Y113827D01*
Y110094D01*
G01X463353Y113694D02*
X465486D01*
X465286Y114627D01*
X464953Y115161D01*
X464486Y115427D01*
X464020Y115294D01*
X463620Y114894D01*
X463353Y113961D01*
X463220Y113160D01*
Y112361D01*
X463353Y111561D01*
X463686Y110761D01*
X464086Y110227D01*
X464553Y110094D01*
X465020Y110361D01*
X465486Y111160D01*
G01X468353Y118094D02*
Y110094D01*
G01X467420Y115427D02*
X469286D01*
G01X471420Y110094D02*
Y115427D01*
G01Y114361D02*
X471753Y114894D01*
X472086Y115294D01*
X472553Y115427D01*
X472886Y115294D01*
X473286Y114894D01*
G01X476353Y115427D02*
Y110094D01*
G01Y117561D02*
X476220Y117694D01*
Y117961D01*
X476353Y118094D01*
X476486Y117961D01*
Y117694D01*
X476353Y117561D01*
G01X481420Y114761D02*
X480953Y115294D01*
X480553Y115427D01*
X480020Y115161D01*
X479620Y114627D01*
X479353Y113694D01*
X479286Y112761D01*
X479353Y111827D01*
X479620Y111027D01*
X480020Y110361D01*
X480553Y110094D01*
X481020Y110361D01*
X481420Y110894D01*
G01X489553Y110094D02*
Y115427D01*
G01Y114494D02*
X489286Y115027D01*
X488886Y115294D01*
X488420Y115427D01*
X487953Y115161D01*
X487553Y114627D01*
X487286Y113827D01*
X487153Y112761D01*
X487286Y111694D01*
X487553Y110894D01*
X487953Y110361D01*
X488420Y110094D01*
X488886Y110227D01*
X489286Y110627D01*
X489553Y111160D01*
G01X491220Y110094D02*
Y115427D01*
G01Y114094D02*
X491486Y114761D01*
X491886Y115294D01*
X492420Y115427D01*
X492886Y115294D01*
X493286Y114761D01*
X493486Y113827D01*
Y110094D01*
G01X497553Y118094D02*
Y110094D01*
G01Y111294D02*
X497286Y110627D01*
X496886Y110227D01*
X496420Y110094D01*
X495886Y110361D01*
X495486Y111027D01*
X495220Y111827D01*
X495153Y112761D01*
X495220Y113694D01*
X495486Y114494D01*
X495886Y115161D01*
X496420Y115427D01*
X496886Y115294D01*
X497220Y115027D01*
X497553Y114494D01*
G01X505686Y110094D02*
X503020D01*
Y118094D01*
X505686D01*
G01X504620Y114227D02*
X503020D01*
G01X507220Y110094D02*
Y115427D01*
G01Y114094D02*
X507486Y114761D01*
X507886Y115294D01*
X508420Y115427D01*
X508886Y115294D01*
X509286Y114761D01*
X509486Y113827D01*
Y110094D01*
G01X511420Y108094D02*
X511886Y107561D01*
X512420Y107427D01*
X512886Y107561D01*
X513286Y108227D01*
X513553Y109161D01*
Y115427D01*
G01Y114361D02*
X513286Y114894D01*
X512886Y115294D01*
X512420Y115427D01*
X511886Y115161D01*
X511553Y114627D01*
X511286Y113694D01*
X511153Y112761D01*
X511220Y111961D01*
X511486Y111027D01*
X511886Y110361D01*
X512420Y110094D01*
X512820Y110227D01*
X513286Y110761D01*
X513553Y111294D01*
G01X516353Y110094D02*
Y118094D01*
G01X520353Y115427D02*
Y110094D01*
G01Y117561D02*
X520220Y117694D01*
Y117961D01*
X520353Y118094D01*
X520486Y117961D01*
Y117694D01*
X520353Y117561D01*
G01X523353Y111027D02*
X523686Y110494D01*
X524153Y110094D01*
X524553D01*
X524953Y110361D01*
X525220Y110761D01*
X525353Y111294D01*
X525286Y112094D01*
X525020Y112494D01*
X523820Y113294D01*
X523553Y114227D01*
X523686Y114894D01*
X523953Y115294D01*
X524353Y115427D01*
X524753Y115294D01*
X525153Y114894D01*
G01X527220Y110094D02*
Y118094D01*
G01Y114227D02*
X527553Y114894D01*
X527886Y115294D01*
X528420Y115427D01*
X528820Y115294D01*
X529286Y114761D01*
X529486Y113961D01*
Y110094D01*
G01X535353Y111027D02*
X535686Y110494D01*
X536153Y110094D01*
X536553D01*
X536953Y110361D01*
X537220Y110761D01*
X537353Y111294D01*
X537286Y112094D01*
X537020Y112494D01*
X535820Y113294D01*
X535553Y114227D01*
X535686Y114894D01*
X535953Y115294D01*
X536353Y115427D01*
X536753Y115294D01*
X537153Y114894D01*
G01X538953Y107694D02*
X539353Y107427D01*
X539886Y107694D01*
X540220Y108227D01*
X540486Y108894D01*
X540886Y111027D01*
X541753Y115427D01*
G01X539620D02*
X540886Y111027D01*
G01X543353D02*
X543686Y110494D01*
X544153Y110094D01*
X544553D01*
X544953Y110361D01*
X545220Y110761D01*
X545353Y111294D01*
X545286Y112094D01*
X545020Y112494D01*
X543820Y113294D01*
X543553Y114227D01*
X543686Y114894D01*
X543953Y115294D01*
X544353Y115427D01*
X544753Y115294D01*
X545153Y114894D01*
G01X548353Y118094D02*
Y110094D01*
G01X547420Y115427D02*
X549286D01*
G01X551353Y113694D02*
X553486D01*
X553286Y114627D01*
X552953Y115161D01*
X552486Y115427D01*
X552020Y115294D01*
X551620Y114894D01*
X551353Y113961D01*
X551220Y113160D01*
Y112361D01*
X551353Y111561D01*
X551686Y110761D01*
X552086Y110227D01*
X552553Y110094D01*
X553020Y110361D01*
X553486Y111160D01*
G01X554353Y110094D02*
Y115427D01*
G01Y113961D02*
X554553Y114627D01*
X554886Y115161D01*
X555353Y115427D01*
X555820Y115161D01*
X556153Y114627D01*
X556353Y113961D01*
Y110094D01*
G01Y113961D02*
X556553Y114627D01*
X556886Y115161D01*
X557353Y115427D01*
X557820Y115161D01*
X558153Y114627D01*
X558353Y113827D01*
Y110094D01*
G01X564353Y115427D02*
Y110094D01*
G01Y117561D02*
X564220Y117694D01*
Y117961D01*
X564353Y118094D01*
X564486Y117961D01*
Y117694D01*
X564353Y117561D01*
G01X567353Y111027D02*
X567686Y110494D01*
X568153Y110094D01*
X568553D01*
X568953Y110361D01*
X569220Y110761D01*
X569353Y111294D01*
X569286Y112094D01*
X569020Y112494D01*
X567820Y113294D01*
X567553Y114227D01*
X567686Y114894D01*
X567953Y115294D01*
X568353Y115427D01*
X568753Y115294D01*
X569153Y114894D01*
G01X576353Y110094D02*
Y118094D01*
G01X579353Y113694D02*
X581486D01*
X581286Y114627D01*
X580953Y115161D01*
X580486Y115427D01*
X580020Y115294D01*
X579620Y114894D01*
X579353Y113961D01*
X579220Y113160D01*
Y112361D01*
X579353Y111561D01*
X579686Y110761D01*
X580086Y110227D01*
X580553Y110094D01*
X581020Y110361D01*
X581486Y111160D01*
G01X583353Y111027D02*
X583686Y110494D01*
X584153Y110094D01*
X584553D01*
X584953Y110361D01*
X585220Y110761D01*
X585353Y111294D01*
X585286Y112094D01*
X585020Y112494D01*
X583820Y113294D01*
X583553Y114227D01*
X583686Y114894D01*
X583953Y115294D01*
X584353Y115427D01*
X584753Y115294D01*
X585153Y114894D01*
G01X587353Y111027D02*
X587686Y110494D01*
X588153Y110094D01*
X588553D01*
X588953Y110361D01*
X589220Y110761D01*
X589353Y111294D01*
X589286Y112094D01*
X589020Y112494D01*
X587820Y113294D01*
X587553Y114227D01*
X587686Y114894D01*
X587953Y115294D01*
X588353Y115427D01*
X588753Y115294D01*
X589153Y114894D01*
G01X596353Y118094D02*
Y110094D01*
G01X595420Y115427D02*
X597286D01*
G01X599220Y110094D02*
Y118094D01*
G01Y114227D02*
X599553Y114894D01*
X599886Y115294D01*
X600420Y115427D01*
X600820Y115294D01*
X601286Y114761D01*
X601486Y113961D01*
Y110094D01*
G01X605553D02*
Y115427D01*
G01Y114494D02*
X605286Y115027D01*
X604886Y115294D01*
X604420Y115427D01*
X603953Y115161D01*
X603553Y114627D01*
X603286Y113827D01*
X603153Y112761D01*
X603286Y111694D01*
X603553Y110894D01*
X603953Y110361D01*
X604420Y110094D01*
X604886Y110227D01*
X605286Y110627D01*
X605553Y111160D01*
G01X607220Y110094D02*
Y115427D01*
G01Y114094D02*
X607486Y114761D01*
X607886Y115294D01*
X608420Y115427D01*
X608886Y115294D01*
X609286Y114761D01*
X609486Y113827D01*
Y110094D01*
G01X616353D02*
Y118094D01*
X615553Y116494D01*
G01Y110094D02*
X617153D01*
G01X622353D02*
Y115427D01*
G01Y113961D02*
X622553Y114627D01*
X622886Y115161D01*
X623353Y115427D01*
X623820Y115161D01*
X624153Y114627D01*
X624353Y113961D01*
Y110094D01*
G01Y113961D02*
X624553Y114627D01*
X624886Y115161D01*
X625353Y115427D01*
X625820Y115161D01*
X626153Y114627D01*
X626353Y113827D01*
Y110094D01*
G01X628353Y115427D02*
Y110094D01*
G01Y117561D02*
X628220Y117694D01*
Y117961D01*
X628353Y118094D01*
X628486Y117961D01*
Y117694D01*
X628353Y117561D01*
G01X632353Y110094D02*
Y118094D01*
G01X636220Y108627D02*
X636486Y110361D01*
G01X643153Y107427D02*
Y115427D01*
G01Y114227D02*
X643486Y114894D01*
X643820Y115294D01*
X644353Y115427D01*
X644820Y115294D01*
X645286Y114627D01*
X645486Y113694D01*
X645553Y112761D01*
X645486Y111827D01*
X645286Y110894D01*
X644886Y110361D01*
X644353Y110094D01*
X643886Y110227D01*
X643420Y110627D01*
X643153Y111160D01*
G01X648353Y110094D02*
Y118094D01*
G01X651353Y113694D02*
X653486D01*
X653286Y114627D01*
X652953Y115161D01*
X652486Y115427D01*
X652020Y115294D01*
X651620Y114894D01*
X651353Y113961D01*
X651220Y113160D01*
Y112361D01*
X651353Y111561D01*
X651686Y110761D01*
X652086Y110227D01*
X652553Y110094D01*
X653020Y110361D01*
X653486Y111160D01*
G01X657553Y110094D02*
Y115427D01*
G01Y114494D02*
X657286Y115027D01*
X656886Y115294D01*
X656420Y115427D01*
X655953Y115161D01*
X655553Y114627D01*
X655286Y113827D01*
X655153Y112761D01*
X655286Y111694D01*
X655553Y110894D01*
X655953Y110361D01*
X656420Y110094D01*
X656886Y110227D01*
X657286Y110627D01*
X657553Y111160D01*
G01X659353Y111027D02*
X659686Y110494D01*
X660153Y110094D01*
X660553D01*
X660953Y110361D01*
X661220Y110761D01*
X661353Y111294D01*
X661286Y112094D01*
X661020Y112494D01*
X659820Y113294D01*
X659553Y114227D01*
X659686Y114894D01*
X659953Y115294D01*
X660353Y115427D01*
X660753Y115294D01*
X661153Y114894D01*
G01X663353Y113694D02*
X665486D01*
X665286Y114627D01*
X664953Y115161D01*
X664486Y115427D01*
X664020Y115294D01*
X663620Y114894D01*
X663353Y113961D01*
X663220Y113160D01*
Y112361D01*
X663353Y111561D01*
X663686Y110761D01*
X664086Y110227D01*
X664553Y110094D01*
X665020Y110361D01*
X665486Y111160D01*
G01X671953Y110094D02*
Y116894D01*
X672086Y117561D01*
X672353Y117961D01*
X672753Y118094D01*
X673153Y117827D01*
X673353Y117161D01*
G01X672553Y114894D02*
X671220D01*
G01X676353Y110094D02*
X675953Y110227D01*
X675553Y110761D01*
X675286Y111694D01*
X675153Y112761D01*
X675286Y113827D01*
X675553Y114761D01*
X675953Y115294D01*
X676353Y115427D01*
X676753Y115294D01*
X677153Y114761D01*
X677420Y113827D01*
X677486Y112761D01*
X677420Y111694D01*
X677153Y110761D01*
X676753Y110227D01*
X676353Y110094D01*
G01X680353D02*
Y118094D01*
G01X684353Y110094D02*
Y118094D01*
G01X688353Y110094D02*
X687953Y110227D01*
X687553Y110761D01*
X687286Y111694D01*
X687153Y112761D01*
X687286Y113827D01*
X687553Y114761D01*
X687953Y115294D01*
X688353Y115427D01*
X688753Y115294D01*
X689153Y114761D01*
X689420Y113827D01*
X689486Y112761D01*
X689420Y111694D01*
X689153Y110761D01*
X688753Y110227D01*
X688353Y110094D01*
G01X690686Y115427D02*
X691486Y110094D01*
X692353Y115427D01*
X693220Y110094D01*
X694020Y115427D01*
G01X698353Y110094D02*
Y115427D01*
G01Y113961D02*
X698553Y114627D01*
X698886Y115161D01*
X699353Y115427D01*
X699820Y115161D01*
X700153Y114627D01*
X700353Y113961D01*
Y110094D01*
G01Y113961D02*
X700553Y114627D01*
X700886Y115161D01*
X701353Y115427D01*
X701820Y115161D01*
X702153Y114627D01*
X702353Y113827D01*
Y110094D01*
G01X703353Y113694D02*
X705486D01*
X705286Y114627D01*
X704953Y115161D01*
X704486Y115427D01*
X704020Y115294D01*
X703620Y114894D01*
X703353Y113961D01*
X703220Y113160D01*
Y112361D01*
X703353Y111561D01*
X703686Y110761D01*
X704086Y110227D01*
X704553Y110094D01*
X705020Y110361D01*
X705486Y111160D01*
G01X709420Y114761D02*
X708953Y115294D01*
X708553Y115427D01*
X708020Y115161D01*
X707620Y114627D01*
X707353Y113694D01*
X707286Y112761D01*
X707353Y111827D01*
X707620Y111027D01*
X708020Y110361D01*
X708553Y110094D01*
X709020Y110361D01*
X709420Y110894D01*
G01X711220Y110094D02*
Y118094D01*
G01Y114227D02*
X711553Y114894D01*
X711886Y115294D01*
X712420Y115427D01*
X712820Y115294D01*
X713286Y114761D01*
X713486Y113961D01*
Y110094D01*
G01X717553D02*
Y115427D01*
G01Y114494D02*
X717286Y115027D01*
X716886Y115294D01*
X716420Y115427D01*
X715953Y115161D01*
X715553Y114627D01*
X715286Y113827D01*
X715153Y112761D01*
X715286Y111694D01*
X715553Y110894D01*
X715953Y110361D01*
X716420Y110094D01*
X716886Y110227D01*
X717286Y110627D01*
X717553Y111160D01*
G01X719220Y110094D02*
Y115427D01*
G01Y114094D02*
X719486Y114761D01*
X719886Y115294D01*
X720420Y115427D01*
X720886Y115294D01*
X721286Y114761D01*
X721486Y113827D01*
Y110094D01*
G01X724353Y115427D02*
Y110094D01*
G01Y117561D02*
X724220Y117694D01*
Y117961D01*
X724353Y118094D01*
X724486Y117961D01*
Y117694D01*
X724353Y117561D01*
G01X729420Y114761D02*
X728953Y115294D01*
X728553Y115427D01*
X728020Y115161D01*
X727620Y114627D01*
X727353Y113694D01*
X727286Y112761D01*
X727353Y111827D01*
X727620Y111027D01*
X728020Y110361D01*
X728553Y110094D01*
X729020Y110361D01*
X729420Y110894D01*
G01X733553Y110094D02*
Y115427D01*
G01Y114494D02*
X733286Y115027D01*
X732886Y115294D01*
X732420Y115427D01*
X731953Y115161D01*
X731553Y114627D01*
X731286Y113827D01*
X731153Y112761D01*
X731286Y111694D01*
X731553Y110894D01*
X731953Y110361D01*
X732420Y110094D01*
X732886Y110227D01*
X733286Y110627D01*
X733553Y111160D01*
G01X736353Y110094D02*
Y118094D01*
G01X745553D02*
Y110094D01*
G01Y111294D02*
X745286Y110627D01*
X744886Y110227D01*
X744420Y110094D01*
X743886Y110361D01*
X743486Y111027D01*
X743220Y111827D01*
X743153Y112761D01*
X743220Y113694D01*
X743486Y114494D01*
X743886Y115161D01*
X744420Y115427D01*
X744886Y115294D01*
X745220Y115027D01*
X745553Y114494D01*
G01X747420Y110094D02*
Y115427D01*
G01Y114361D02*
X747753Y114894D01*
X748086Y115294D01*
X748553Y115427D01*
X748886Y115294D01*
X749286Y114894D01*
G01X753553Y110094D02*
Y115427D01*
G01Y114494D02*
X753286Y115027D01*
X752886Y115294D01*
X752420Y115427D01*
X751953Y115161D01*
X751553Y114627D01*
X751286Y113827D01*
X751153Y112761D01*
X751286Y111694D01*
X751553Y110894D01*
X751953Y110361D01*
X752420Y110094D01*
X752886Y110227D01*
X753286Y110627D01*
X753553Y111160D01*
G01X754686Y115427D02*
X755486Y110094D01*
X756353Y115427D01*
X757220Y110094D01*
X758020Y115427D01*
G01X760353D02*
Y110094D01*
G01Y117561D02*
X760220Y117694D01*
Y117961D01*
X760353Y118094D01*
X760486Y117961D01*
Y117694D01*
X760353Y117561D01*
G01X763220Y110094D02*
Y115427D01*
G01Y114094D02*
X763486Y114761D01*
X763886Y115294D01*
X764420Y115427D01*
X764886Y115294D01*
X765286Y114761D01*
X765486Y113827D01*
Y110094D01*
G01X767420Y108094D02*
X767886Y107561D01*
X768420Y107427D01*
X768886Y107561D01*
X769286Y108227D01*
X769553Y109161D01*
Y115427D01*
G01Y114361D02*
X769286Y114894D01*
X768886Y115294D01*
X768420Y115427D01*
X767886Y115161D01*
X767553Y114627D01*
X767286Y113694D01*
X767153Y112761D01*
X767220Y111961D01*
X767486Y111027D01*
X767886Y110361D01*
X768420Y110094D01*
X768820Y110227D01*
X769286Y110761D01*
X769553Y111294D01*
G01X771886Y107694D02*
X772820Y109561D01*
Y111427D01*
X771886D01*
Y109561D01*
X772820D01*
G01Y112761D02*
Y114627D01*
X771886D01*
Y112761D01*
X772820D01*
G01X338753Y105794D02*
X340353D01*
G01X339553D02*
Y97794D01*
G01X338753D02*
X340353D01*
G01X343153D02*
Y104594D01*
X343286Y105261D01*
X343553Y105661D01*
X343953Y105794D01*
X344353Y105527D01*
X344553Y104861D01*
G01X343753Y102594D02*
X342420D01*
G01X351553Y103127D02*
Y97794D01*
G01Y105261D02*
X351420Y105394D01*
Y105661D01*
X351553Y105794D01*
X351686Y105661D01*
Y105394D01*
X351553Y105261D01*
G01X354553Y98727D02*
X354886Y98194D01*
X355353Y97794D01*
X355753D01*
X356153Y98061D01*
X356420Y98461D01*
X356553Y98994D01*
X356486Y99794D01*
X356220Y100194D01*
X355020Y100994D01*
X354753Y101927D01*
X354886Y102594D01*
X355153Y102994D01*
X355553Y103127D01*
X355953Y102994D01*
X356353Y102594D01*
G01X362620Y95794D02*
X363086Y95261D01*
X363620Y95127D01*
X364086Y95261D01*
X364486Y95927D01*
X364753Y96861D01*
Y103127D01*
G01Y102061D02*
X364486Y102594D01*
X364086Y102994D01*
X363620Y103127D01*
X363086Y102861D01*
X362753Y102327D01*
X362486Y101394D01*
X362353Y100461D01*
X362420Y99661D01*
X362686Y98727D01*
X363086Y98061D01*
X363620Y97794D01*
X364020Y97927D01*
X364486Y98461D01*
X364753Y98994D01*
G01X366620Y97794D02*
Y103127D01*
G01Y102061D02*
X366953Y102594D01*
X367286Y102994D01*
X367753Y103127D01*
X368086Y102994D01*
X368486Y102594D01*
G01X370553Y101394D02*
X372686D01*
X372486Y102327D01*
X372153Y102861D01*
X371686Y103127D01*
X371220Y102994D01*
X370820Y102594D01*
X370553Y101661D01*
X370420Y100860D01*
Y100061D01*
X370553Y99261D01*
X370886Y98461D01*
X371286Y97927D01*
X371753Y97794D01*
X372220Y98061D01*
X372686Y98860D01*
G01X376753Y97794D02*
Y103127D01*
G01Y102194D02*
X376486Y102727D01*
X376086Y102994D01*
X375620Y103127D01*
X375153Y102861D01*
X374753Y102327D01*
X374486Y101527D01*
X374353Y100461D01*
X374486Y99394D01*
X374753Y98594D01*
X375153Y98061D01*
X375620Y97794D01*
X376086Y97927D01*
X376486Y98327D01*
X376753Y98860D01*
G01X379553Y105794D02*
Y97794D01*
G01X378620Y103127D02*
X380486D01*
G01X382553Y101394D02*
X384686D01*
X384486Y102327D01*
X384153Y102861D01*
X383686Y103127D01*
X383220Y102994D01*
X382820Y102594D01*
X382553Y101661D01*
X382420Y100860D01*
Y100061D01*
X382553Y99261D01*
X382886Y98461D01*
X383286Y97927D01*
X383753Y97794D01*
X384220Y98061D01*
X384686Y98860D01*
G01X386620Y97794D02*
Y103127D01*
G01Y102061D02*
X386953Y102594D01*
X387286Y102994D01*
X387753Y103127D01*
X388086Y102994D01*
X388486Y102594D01*
G01X395553Y105794D02*
Y97794D01*
G01X394620Y103127D02*
X396486D01*
G01X398420Y97794D02*
Y105794D01*
G01Y101927D02*
X398753Y102594D01*
X399086Y102994D01*
X399620Y103127D01*
X400020Y102994D01*
X400486Y102461D01*
X400686Y101661D01*
Y97794D01*
G01X404753D02*
Y103127D01*
G01Y102194D02*
X404486Y102727D01*
X404086Y102994D01*
X403620Y103127D01*
X403153Y102861D01*
X402753Y102327D01*
X402486Y101527D01*
X402353Y100461D01*
X402486Y99394D01*
X402753Y98594D01*
X403153Y98061D01*
X403620Y97794D01*
X404086Y97927D01*
X404486Y98327D01*
X404753Y98860D01*
G01X406420Y97794D02*
Y103127D01*
G01Y101794D02*
X406686Y102461D01*
X407086Y102994D01*
X407620Y103127D01*
X408086Y102994D01*
X408486Y102461D01*
X408686Y101527D01*
Y97794D01*
G01X415553D02*
Y105794D01*
X414753Y104194D01*
G01Y97794D02*
X416353D01*
G01X421553D02*
Y103127D01*
G01Y101661D02*
X421753Y102327D01*
X422086Y102861D01*
X422553Y103127D01*
X423020Y102861D01*
X423353Y102327D01*
X423553Y101661D01*
Y97794D01*
G01Y101661D02*
X423753Y102327D01*
X424086Y102861D01*
X424553Y103127D01*
X425020Y102861D01*
X425353Y102327D01*
X425553Y101527D01*
Y97794D01*
G01X427553Y103127D02*
Y97794D01*
G01Y105261D02*
X427420Y105394D01*
Y105661D01*
X427553Y105794D01*
X427686Y105661D01*
Y105394D01*
X427553Y105261D01*
G01X430553Y98727D02*
X430886Y98194D01*
X431353Y97794D01*
X431753D01*
X432153Y98061D01*
X432420Y98461D01*
X432553Y98994D01*
X432486Y99794D01*
X432220Y100194D01*
X431020Y100994D01*
X430753Y101927D01*
X430886Y102594D01*
X431153Y102994D01*
X431553Y103127D01*
X431953Y102994D01*
X432353Y102594D01*
G01X435420Y96327D02*
X435686Y98061D01*
G01X442353Y95127D02*
Y103127D01*
G01Y101927D02*
X442686Y102594D01*
X443020Y102994D01*
X443553Y103127D01*
X444020Y102994D01*
X444486Y102327D01*
X444686Y101394D01*
X444753Y100461D01*
X444686Y99527D01*
X444486Y98594D01*
X444086Y98061D01*
X443553Y97794D01*
X443086Y97927D01*
X442620Y98327D01*
X442353Y98860D01*
G01X447553Y97794D02*
Y105794D01*
G01X450553Y101394D02*
X452686D01*
X452486Y102327D01*
X452153Y102861D01*
X451686Y103127D01*
X451220Y102994D01*
X450820Y102594D01*
X450553Y101661D01*
X450420Y100860D01*
Y100061D01*
X450553Y99261D01*
X450886Y98461D01*
X451286Y97927D01*
X451753Y97794D01*
X452220Y98061D01*
X452686Y98860D01*
G01X456753Y97794D02*
Y103127D01*
G01Y102194D02*
X456486Y102727D01*
X456086Y102994D01*
X455620Y103127D01*
X455153Y102861D01*
X454753Y102327D01*
X454486Y101527D01*
X454353Y100461D01*
X454486Y99394D01*
X454753Y98594D01*
X455153Y98061D01*
X455620Y97794D01*
X456086Y97927D01*
X456486Y98327D01*
X456753Y98860D01*
G01X458553Y98727D02*
X458886Y98194D01*
X459353Y97794D01*
X459753D01*
X460153Y98061D01*
X460420Y98461D01*
X460553Y98994D01*
X460486Y99794D01*
X460220Y100194D01*
X459020Y100994D01*
X458753Y101927D01*
X458886Y102594D01*
X459153Y102994D01*
X459553Y103127D01*
X459953Y102994D01*
X460353Y102594D01*
G01X462553Y101394D02*
X464686D01*
X464486Y102327D01*
X464153Y102861D01*
X463686Y103127D01*
X463220Y102994D01*
X462820Y102594D01*
X462553Y101661D01*
X462420Y100860D01*
Y100061D01*
X462553Y99261D01*
X462886Y98461D01*
X463286Y97927D01*
X463753Y97794D01*
X464220Y98061D01*
X464686Y98860D01*
G01X471553Y103127D02*
Y97794D01*
G01Y105261D02*
X471420Y105394D01*
Y105661D01*
X471553Y105794D01*
X471686Y105661D01*
Y105394D01*
X471553Y105261D01*
G01X474553Y98727D02*
X474886Y98194D01*
X475353Y97794D01*
X475753D01*
X476153Y98061D01*
X476420Y98461D01*
X476553Y98994D01*
X476486Y99794D01*
X476220Y100194D01*
X475020Y100994D01*
X474753Y101927D01*
X474886Y102594D01*
X475153Y102994D01*
X475553Y103127D01*
X475953Y102994D01*
X476353Y102594D01*
G01X478553Y98727D02*
X478886Y98194D01*
X479353Y97794D01*
X479753D01*
X480153Y98061D01*
X480420Y98461D01*
X480553Y98994D01*
X480486Y99794D01*
X480220Y100194D01*
X479020Y100994D01*
X478753Y101927D01*
X478886Y102594D01*
X479153Y102994D01*
X479553Y103127D01*
X479953Y102994D01*
X480353Y102594D01*
G01X482420Y103127D02*
Y99394D01*
X482686Y98461D01*
X483086Y97927D01*
X483553Y97794D01*
X484020Y97927D01*
X484420Y98461D01*
X484686Y99394D01*
G01Y97794D02*
Y103127D01*
G01X486553Y101394D02*
X488686D01*
X488486Y102327D01*
X488153Y102861D01*
X487686Y103127D01*
X487220Y102994D01*
X486820Y102594D01*
X486553Y101661D01*
X486420Y100860D01*
Y100061D01*
X486553Y99261D01*
X486886Y98461D01*
X487286Y97927D01*
X487753Y97794D01*
X488220Y98061D01*
X488686Y98860D01*
G01X494553Y101394D02*
X496686D01*
X496486Y102327D01*
X496153Y102861D01*
X495686Y103127D01*
X495220Y102994D01*
X494820Y102594D01*
X494553Y101661D01*
X494420Y100860D01*
Y100061D01*
X494553Y99261D01*
X494886Y98461D01*
X495286Y97927D01*
X495753Y97794D01*
X496220Y98061D01*
X496686Y98860D01*
G01X498420Y97794D02*
Y103127D01*
G01Y101794D02*
X498686Y102461D01*
X499086Y102994D01*
X499620Y103127D01*
X500086Y102994D01*
X500486Y102461D01*
X500686Y101527D01*
Y97794D01*
G01X502620Y95794D02*
X503086Y95261D01*
X503620Y95127D01*
X504086Y95261D01*
X504486Y95927D01*
X504753Y96861D01*
Y103127D01*
G01Y102061D02*
X504486Y102594D01*
X504086Y102994D01*
X503620Y103127D01*
X503086Y102861D01*
X502753Y102327D01*
X502486Y101394D01*
X502353Y100461D01*
X502420Y99661D01*
X502686Y98727D01*
X503086Y98061D01*
X503620Y97794D01*
X504020Y97927D01*
X504486Y98461D01*
X504753Y98994D01*
G01X507553Y103127D02*
Y97794D01*
G01Y105261D02*
X507420Y105394D01*
Y105661D01*
X507553Y105794D01*
X507686Y105661D01*
Y105394D01*
X507553Y105261D01*
G01X510420Y97794D02*
Y103127D01*
G01Y101794D02*
X510686Y102461D01*
X511086Y102994D01*
X511620Y103127D01*
X512086Y102994D01*
X512486Y102461D01*
X512686Y101527D01*
Y97794D01*
G01X514553Y101394D02*
X516686D01*
X516486Y102327D01*
X516153Y102861D01*
X515686Y103127D01*
X515220Y102994D01*
X514820Y102594D01*
X514553Y101661D01*
X514420Y100860D01*
Y100061D01*
X514553Y99261D01*
X514886Y98461D01*
X515286Y97927D01*
X515753Y97794D01*
X516220Y98061D01*
X516686Y98860D01*
G01X518553Y101394D02*
X520686D01*
X520486Y102327D01*
X520153Y102861D01*
X519686Y103127D01*
X519220Y102994D01*
X518820Y102594D01*
X518553Y101661D01*
X518420Y100860D01*
Y100061D01*
X518553Y99261D01*
X518886Y98461D01*
X519286Y97927D01*
X519753Y97794D01*
X520220Y98061D01*
X520686Y98860D01*
G01X522620Y97794D02*
Y103127D01*
G01Y102061D02*
X522953Y102594D01*
X523286Y102994D01*
X523753Y103127D01*
X524086Y102994D01*
X524486Y102594D01*
G01X527553Y103127D02*
Y97794D01*
G01Y105261D02*
X527420Y105394D01*
Y105661D01*
X527553Y105794D01*
X527686Y105661D01*
Y105394D01*
X527553Y105261D01*
G01X530420Y97794D02*
Y103127D01*
G01Y101794D02*
X530686Y102461D01*
X531086Y102994D01*
X531620Y103127D01*
X532086Y102994D01*
X532486Y102461D01*
X532686Y101527D01*
Y97794D01*
G01X534620Y95794D02*
X535086Y95261D01*
X535620Y95127D01*
X536086Y95261D01*
X536486Y95927D01*
X536753Y96861D01*
Y103127D01*
G01Y102061D02*
X536486Y102594D01*
X536086Y102994D01*
X535620Y103127D01*
X535086Y102861D01*
X534753Y102327D01*
X534486Y101394D01*
X534353Y100461D01*
X534420Y99661D01*
X534686Y98727D01*
X535086Y98061D01*
X535620Y97794D01*
X536020Y97927D01*
X536486Y98461D01*
X536753Y98994D01*
G01X544753Y95127D02*
Y103127D01*
G01Y101927D02*
X544420Y102594D01*
X544020Y102994D01*
X543553Y103127D01*
X543153Y102994D01*
X542686Y102327D01*
X542420Y101394D01*
X542353Y100461D01*
X542420Y99527D01*
X542686Y98594D01*
X543153Y97927D01*
X543553Y97794D01*
X544020Y97927D01*
X544420Y98327D01*
X544753Y98994D01*
G01X546420Y103127D02*
Y99394D01*
X546686Y98461D01*
X547086Y97927D01*
X547553Y97794D01*
X548020Y97927D01*
X548420Y98461D01*
X548686Y99394D01*
G01Y97794D02*
Y103127D01*
G01X550553Y101394D02*
X552686D01*
X552486Y102327D01*
X552153Y102861D01*
X551686Y103127D01*
X551220Y102994D01*
X550820Y102594D01*
X550553Y101661D01*
X550420Y100860D01*
Y100061D01*
X550553Y99261D01*
X550886Y98461D01*
X551286Y97927D01*
X551753Y97794D01*
X552220Y98061D01*
X552686Y98860D01*
G01X554620Y97794D02*
Y103127D01*
G01Y102061D02*
X554953Y102594D01*
X555286Y102994D01*
X555753Y103127D01*
X556086Y102994D01*
X556486Y102594D01*
G01X558153Y95394D02*
X558553Y95127D01*
X559086Y95394D01*
X559420Y95927D01*
X559686Y96594D01*
X560086Y98727D01*
X560953Y103127D01*
G01X558820D02*
X560086Y98727D01*
G01X563553Y97527D02*
X563420Y97661D01*
Y97927D01*
X563553Y98061D01*
X563686Y97927D01*
Y97661D01*
X563553Y97527D01*
G01X338686Y129894D02*
Y124161D01*
X338953Y122960D01*
X339486Y122161D01*
X340153Y121894D01*
X340820Y122161D01*
X341353Y122960D01*
X341620Y124161D01*
Y129894D01*
G01X343020Y121894D02*
Y127227D01*
G01Y125894D02*
X343286Y126561D01*
X343686Y127094D01*
X344220Y127227D01*
X344686Y127094D01*
X345086Y126561D01*
X345286Y125627D01*
Y121894D01*
G01X348153Y127227D02*
Y121894D01*
G01Y129361D02*
X348020Y129494D01*
Y129761D01*
X348153Y129894D01*
X348286Y129761D01*
Y129494D01*
X348153Y129361D01*
G01X352153Y129894D02*
Y121894D01*
G01X351220Y127227D02*
X353086D01*
G01X361220Y126561D02*
X360753Y127094D01*
X360353Y127227D01*
X359820Y126961D01*
X359420Y126427D01*
X359153Y125494D01*
X359086Y124561D01*
X359153Y123627D01*
X359420Y122827D01*
X359820Y122161D01*
X360353Y121894D01*
X360820Y122161D01*
X361220Y122694D01*
G01X364153Y121894D02*
X363753Y122027D01*
X363353Y122561D01*
X363086Y123494D01*
X362953Y124561D01*
X363086Y125627D01*
X363353Y126561D01*
X363753Y127094D01*
X364153Y127227D01*
X364553Y127094D01*
X364953Y126561D01*
X365220Y125627D01*
X365286Y124561D01*
X365220Y123494D01*
X364953Y122561D01*
X364553Y122027D01*
X364153Y121894D01*
G01X367020D02*
Y127227D01*
G01Y125894D02*
X367286Y126561D01*
X367686Y127094D01*
X368220Y127227D01*
X368686Y127094D01*
X369086Y126561D01*
X369286Y125627D01*
Y121894D01*
G01X370953Y127227D02*
X372153Y121894D01*
X373353Y127227D01*
G01X375153Y125494D02*
X377286D01*
X377086Y126427D01*
X376753Y126961D01*
X376286Y127227D01*
X375820Y127094D01*
X375420Y126694D01*
X375153Y125761D01*
X375020Y124960D01*
Y124161D01*
X375153Y123361D01*
X375486Y122561D01*
X375886Y122027D01*
X376353Y121894D01*
X376820Y122161D01*
X377286Y122960D01*
G01X379220Y121894D02*
Y127227D01*
G01Y126161D02*
X379553Y126694D01*
X379886Y127094D01*
X380353Y127227D01*
X380686Y127094D01*
X381086Y126694D01*
G01X383153Y122827D02*
X383486Y122294D01*
X383953Y121894D01*
X384353D01*
X384753Y122161D01*
X385020Y122561D01*
X385153Y123094D01*
X385086Y123894D01*
X384820Y124294D01*
X383620Y125094D01*
X383353Y126027D01*
X383486Y126694D01*
X383753Y127094D01*
X384153Y127227D01*
X384553Y127094D01*
X384953Y126694D01*
G01X388153Y127227D02*
Y121894D01*
G01Y129361D02*
X388020Y129494D01*
Y129761D01*
X388153Y129894D01*
X388286Y129761D01*
Y129494D01*
X388153Y129361D01*
G01X392153Y121894D02*
X391753Y122027D01*
X391353Y122561D01*
X391086Y123494D01*
X390953Y124561D01*
X391086Y125627D01*
X391353Y126561D01*
X391753Y127094D01*
X392153Y127227D01*
X392553Y127094D01*
X392953Y126561D01*
X393220Y125627D01*
X393286Y124561D01*
X393220Y123494D01*
X392953Y122561D01*
X392553Y122027D01*
X392153Y121894D01*
G01X395020D02*
Y127227D01*
G01Y125894D02*
X395286Y126561D01*
X395686Y127094D01*
X396220Y127227D01*
X396686Y127094D01*
X397086Y126561D01*
X397286Y125627D01*
Y121894D01*
G01X404153Y127227D02*
Y121894D01*
G01Y129361D02*
X404020Y129494D01*
Y129761D01*
X404153Y129894D01*
X404286Y129761D01*
Y129494D01*
X404153Y129361D01*
G01X407153Y122827D02*
X407486Y122294D01*
X407953Y121894D01*
X408353D01*
X408753Y122161D01*
X409020Y122561D01*
X409153Y123094D01*
X409086Y123894D01*
X408820Y124294D01*
X407620Y125094D01*
X407353Y126027D01*
X407486Y126694D01*
X407753Y127094D01*
X408153Y127227D01*
X408553Y127094D01*
X408953Y126694D01*
G01X411153Y122827D02*
X411486Y122294D01*
X411953Y121894D01*
X412353D01*
X412753Y122161D01*
X413020Y122561D01*
X413153Y123094D01*
X413086Y123894D01*
X412820Y124294D01*
X411620Y125094D01*
X411353Y126027D01*
X411486Y126694D01*
X411753Y127094D01*
X412153Y127227D01*
X412553Y127094D01*
X412953Y126694D01*
G01X415020Y127227D02*
Y123494D01*
X415286Y122561D01*
X415686Y122027D01*
X416153Y121894D01*
X416620Y122027D01*
X417020Y122561D01*
X417286Y123494D01*
G01Y121894D02*
Y127227D01*
G01X419153Y125494D02*
X421286D01*
X421086Y126427D01*
X420753Y126961D01*
X420286Y127227D01*
X419820Y127094D01*
X419420Y126694D01*
X419153Y125761D01*
X419020Y124960D01*
Y124161D01*
X419153Y123361D01*
X419486Y122561D01*
X419886Y122027D01*
X420353Y121894D01*
X420820Y122161D01*
X421286Y122960D01*
G01X424153Y121627D02*
X424020Y121761D01*
Y122027D01*
X424153Y122161D01*
X424286Y122027D01*
Y121761D01*
X424153Y121627D01*
G01Y125227D02*
X424020Y125361D01*
Y125627D01*
X424153Y125761D01*
X424286Y125627D01*
Y125361D01*
X424153Y125227D01*
G01X344153Y161294D02*
Y169294D01*
X343353Y167694D01*
G01Y161294D02*
X344953D01*
G01X348153D02*
Y169294D01*
X347353Y167694D01*
G01Y161294D02*
X348953D01*
G01X343653Y173794D02*
Y181794D01*
X342853Y180194D01*
G01Y173794D02*
X344453D01*
G01X347653Y181794D02*
X347120Y181527D01*
X346720Y180861D01*
X346453Y180061D01*
X346253Y178994D01*
X346186Y177794D01*
X346253Y176594D01*
X346453Y175527D01*
X346720Y174727D01*
X347120Y174061D01*
X347653Y173794D01*
X348186Y174061D01*
X348586Y174727D01*
X348853Y175527D01*
X349053Y176594D01*
X349120Y177794D01*
X349053Y178994D01*
X348853Y180061D01*
X348586Y180861D01*
X348186Y181527D01*
X347653Y181794D01*
G01X347020Y187727D02*
X347486Y187061D01*
X348020Y186794D01*
X348553Y187061D01*
X349020Y187860D01*
X349353Y189061D01*
X349486Y190261D01*
Y191727D01*
X349353Y192927D01*
X349020Y193994D01*
X348620Y194527D01*
X348153Y194794D01*
X347620Y194527D01*
X347220Y193994D01*
X346953Y193194D01*
X346820Y192127D01*
X346953Y191194D01*
X347286Y190261D01*
X347686Y189727D01*
X348153Y189594D01*
X348686Y189860D01*
X349086Y190527D01*
X349486Y191727D01*
G01X348153Y199294D02*
X348620Y199427D01*
X349153Y199827D01*
X349486Y200494D01*
X349620Y201427D01*
X349486Y202360D01*
X349086Y203161D01*
X348486Y203561D01*
X347820D01*
X347420Y203827D01*
X347086Y204494D01*
X346953Y205427D01*
X347153Y206361D01*
X347620Y207027D01*
X348153Y207294D01*
X348686Y207027D01*
X349153Y206361D01*
X349353Y205427D01*
X349220Y204494D01*
X348886Y203827D01*
X348486Y203561D01*
X347820D01*
X347220Y203161D01*
X346820Y202360D01*
X346686Y201427D01*
X346820Y200494D01*
X347153Y199827D01*
X347686Y199427D01*
X348153Y199294D01*
G01X348020Y211294D02*
X348153Y213027D01*
X348353Y214494D01*
X348620Y215827D01*
X348953Y217294D01*
X349486Y219294D01*
X346820D01*
G01X347386Y227627D02*
X347853Y228561D01*
X348253Y229094D01*
X348786Y229361D01*
X349253Y229094D01*
X349586Y228561D01*
X349853Y227761D01*
X349920Y226827D01*
X349853Y226027D01*
X349586Y225227D01*
X349186Y224561D01*
X348720Y224294D01*
X348186Y224561D01*
X347720Y225360D01*
X347453Y226561D01*
X347386Y227894D01*
X347520Y229627D01*
X347720Y230561D01*
X348053Y231494D01*
X348520Y232161D01*
X348986Y232294D01*
X349453Y232027D01*
X349786Y231361D01*
G01X349453Y262294D02*
Y270294D01*
X346986Y264561D01*
X350320D01*
G01X347186Y244994D02*
X347586Y244327D01*
X348053Y243927D01*
X348653Y243794D01*
X349253Y244061D01*
X349720Y244594D01*
X350053Y245527D01*
X350120Y246594D01*
X349986Y247661D01*
X349653Y248327D01*
X349186Y248861D01*
X348720Y248994D01*
X348253Y248861D01*
X347653Y248327D01*
X347853Y251794D01*
X349653D01*
G01X347186Y287894D02*
X347586Y286961D01*
X348120Y286427D01*
X348720Y286294D01*
X349253Y286427D01*
X349786Y287094D01*
X350120Y287894D01*
X350186Y288694D01*
X350053Y289627D01*
X349586Y290294D01*
X349120Y290561D01*
X348520D01*
G01X349120D02*
X349520Y290961D01*
X349853Y291627D01*
X349986Y292427D01*
X349853Y293227D01*
X349520Y293894D01*
X348920Y294294D01*
X348320Y294161D01*
X347720Y293627D01*
G01X347886Y305961D02*
X348286Y306761D01*
X348753Y307161D01*
X349286Y307294D01*
X349953Y307027D01*
X350420Y306361D01*
X350553Y305561D01*
X350486Y304760D01*
X350220Y304094D01*
X348886Y302761D01*
X348286Y301827D01*
X347886Y300494D01*
X347753Y299294D01*
X350553D01*
G01X349153Y311794D02*
Y319794D01*
X348353Y318194D01*
G01Y311794D02*
X349953D01*
G01X340120Y327294D02*
Y335294D01*
X343186Y327294D01*
Y335294D01*
G01X345653Y327294D02*
X345120Y327427D01*
X344653Y327961D01*
X344253Y328761D01*
X343986Y329694D01*
X343853Y330761D01*
Y331827D01*
X343986Y332894D01*
X344253Y333827D01*
X344653Y334627D01*
X345120Y335161D01*
X345653Y335294D01*
X346186Y335161D01*
X346653Y334627D01*
X347053Y333827D01*
X347320Y332894D01*
X347453Y331827D01*
Y330761D01*
X347320Y329694D01*
X347053Y328761D01*
X346653Y327961D01*
X346186Y327427D01*
X345653Y327294D01*
G01X349653Y327027D02*
X349520Y327161D01*
Y327427D01*
X349653Y327561D01*
X349786Y327427D01*
Y327161D01*
X349653Y327027D01*
G01X395853Y71394D02*
Y63394D01*
G01X394320Y71394D02*
X397386D01*
G01X398720Y63394D02*
Y71394D01*
G01Y67527D02*
X399053Y68194D01*
X399386Y68594D01*
X399920Y68727D01*
X400320Y68594D01*
X400786Y68061D01*
X400986Y67261D01*
Y63394D01*
G01X402853Y66994D02*
X404986D01*
X404786Y67927D01*
X404453Y68461D01*
X403986Y68727D01*
X403520Y68594D01*
X403120Y68194D01*
X402853Y67261D01*
X402720Y66460D01*
Y65661D01*
X402853Y64861D01*
X403186Y64061D01*
X403586Y63527D01*
X404053Y63394D01*
X404520Y63661D01*
X404986Y64460D01*
G01X406920Y63394D02*
Y68727D01*
G01Y67661D02*
X407253Y68194D01*
X407586Y68594D01*
X408053Y68727D01*
X408386Y68594D01*
X408786Y68194D01*
G01X410853Y66994D02*
X412986D01*
X412786Y67927D01*
X412453Y68461D01*
X411986Y68727D01*
X411520Y68594D01*
X411120Y68194D01*
X410853Y67261D01*
X410720Y66460D01*
Y65661D01*
X410853Y64861D01*
X411186Y64061D01*
X411586Y63527D01*
X412053Y63394D01*
X412520Y63661D01*
X412986Y64460D01*
G01X415453Y63394D02*
Y70194D01*
X415586Y70861D01*
X415853Y71261D01*
X416253Y71394D01*
X416653Y71127D01*
X416853Y70461D01*
G01X416053Y68194D02*
X414720D01*
G01X419853Y63394D02*
X419453Y63527D01*
X419053Y64061D01*
X418786Y64994D01*
X418653Y66061D01*
X418786Y67127D01*
X419053Y68061D01*
X419453Y68594D01*
X419853Y68727D01*
X420253Y68594D01*
X420653Y68061D01*
X420920Y67127D01*
X420986Y66061D01*
X420920Y64994D01*
X420653Y64061D01*
X420253Y63527D01*
X419853Y63394D01*
G01X422920D02*
Y68727D01*
G01Y67661D02*
X423253Y68194D01*
X423586Y68594D01*
X424053Y68727D01*
X424386Y68594D01*
X424786Y68194D01*
G01X426853Y66994D02*
X428986D01*
X428786Y67927D01*
X428453Y68461D01*
X427986Y68727D01*
X427520Y68594D01*
X427120Y68194D01*
X426853Y67261D01*
X426720Y66460D01*
Y65661D01*
X426853Y64861D01*
X427186Y64061D01*
X427586Y63527D01*
X428053Y63394D01*
X428520Y63661D01*
X428986Y64460D01*
G01X431720Y61927D02*
X431986Y63661D01*
G01X438653Y60727D02*
Y68727D01*
G01Y67527D02*
X438986Y68194D01*
X439320Y68594D01*
X439853Y68727D01*
X440320Y68594D01*
X440786Y67927D01*
X440986Y66994D01*
X441053Y66061D01*
X440986Y65127D01*
X440786Y64194D01*
X440386Y63661D01*
X439853Y63394D01*
X439386Y63527D01*
X438920Y63927D01*
X438653Y64460D01*
G01X443853Y63394D02*
Y71394D01*
G01X446853Y66994D02*
X448986D01*
X448786Y67927D01*
X448453Y68461D01*
X447986Y68727D01*
X447520Y68594D01*
X447120Y68194D01*
X446853Y67261D01*
X446720Y66460D01*
Y65661D01*
X446853Y64861D01*
X447186Y64061D01*
X447586Y63527D01*
X448053Y63394D01*
X448520Y63661D01*
X448986Y64460D01*
G01X453053Y63394D02*
Y68727D01*
G01Y67794D02*
X452786Y68327D01*
X452386Y68594D01*
X451920Y68727D01*
X451453Y68461D01*
X451053Y67927D01*
X450786Y67127D01*
X450653Y66061D01*
X450786Y64994D01*
X451053Y64194D01*
X451453Y63661D01*
X451920Y63394D01*
X452386Y63527D01*
X452786Y63927D01*
X453053Y64460D01*
G01X454853Y64327D02*
X455186Y63794D01*
X455653Y63394D01*
X456053D01*
X456453Y63661D01*
X456720Y64061D01*
X456853Y64594D01*
X456786Y65394D01*
X456520Y65794D01*
X455320Y66594D01*
X455053Y67527D01*
X455186Y68194D01*
X455453Y68594D01*
X455853Y68727D01*
X456253Y68594D01*
X456653Y68194D01*
G01X458853Y66994D02*
X460986D01*
X460786Y67927D01*
X460453Y68461D01*
X459986Y68727D01*
X459520Y68594D01*
X459120Y68194D01*
X458853Y67261D01*
X458720Y66460D01*
Y65661D01*
X458853Y64861D01*
X459186Y64061D01*
X459586Y63527D01*
X460053Y63394D01*
X460520Y63661D01*
X460986Y64460D01*
G01X467453Y63394D02*
Y70194D01*
X467586Y70861D01*
X467853Y71261D01*
X468253Y71394D01*
X468653Y71127D01*
X468853Y70461D01*
G01X468053Y68194D02*
X466720D01*
G01X471853Y63394D02*
X471453Y63527D01*
X471053Y64061D01*
X470786Y64994D01*
X470653Y66061D01*
X470786Y67127D01*
X471053Y68061D01*
X471453Y68594D01*
X471853Y68727D01*
X472253Y68594D01*
X472653Y68061D01*
X472920Y67127D01*
X472986Y66061D01*
X472920Y64994D01*
X472653Y64061D01*
X472253Y63527D01*
X471853Y63394D01*
G01X475853D02*
Y71394D01*
G01X479853Y63394D02*
Y71394D01*
G01X483853Y63394D02*
X483453Y63527D01*
X483053Y64061D01*
X482786Y64994D01*
X482653Y66061D01*
X482786Y67127D01*
X483053Y68061D01*
X483453Y68594D01*
X483853Y68727D01*
X484253Y68594D01*
X484653Y68061D01*
X484920Y67127D01*
X484986Y66061D01*
X484920Y64994D01*
X484653Y64061D01*
X484253Y63527D01*
X483853Y63394D01*
G01X486186Y68727D02*
X486986Y63394D01*
X487853Y68727D01*
X488720Y63394D01*
X489520Y68727D01*
G01X494386Y64994D02*
X494786Y64061D01*
X495320Y63527D01*
X495920Y63394D01*
X496453Y63527D01*
X496986Y64194D01*
X497320Y64994D01*
X497386Y65794D01*
X497253Y66727D01*
X496786Y67394D01*
X496320Y67661D01*
X495720D01*
G01X496320D02*
X496720Y68061D01*
X497053Y68727D01*
X497186Y69527D01*
X497053Y70327D01*
X496720Y70994D01*
X496120Y71394D01*
X495520Y71261D01*
X494920Y70727D01*
G01X499853Y63127D02*
X499720Y63261D01*
Y63527D01*
X499853Y63661D01*
X499986Y63527D01*
Y63261D01*
X499853Y63127D01*
G01X503853Y63394D02*
Y71394D01*
X503053Y69794D01*
G01Y63394D02*
X504653D01*
G01X507853D02*
X508320Y63527D01*
X508853Y63927D01*
X509186Y64594D01*
X509320Y65527D01*
X509186Y66460D01*
X508786Y67261D01*
X508186Y67661D01*
X507520D01*
X507120Y67927D01*
X506786Y68594D01*
X506653Y69527D01*
X506853Y70461D01*
X507320Y71127D01*
X507853Y71394D01*
X508386Y71127D01*
X508853Y70461D01*
X509053Y69527D01*
X508920Y68594D01*
X508586Y67927D01*
X508186Y67661D01*
X507520D01*
X506920Y67261D01*
X506520Y66460D01*
X506386Y65527D01*
X506520Y64594D01*
X506853Y63927D01*
X507386Y63527D01*
X507853Y63394D01*
G01X509853D02*
Y68727D01*
G01Y67261D02*
X510053Y67927D01*
X510386Y68461D01*
X510853Y68727D01*
X511320Y68461D01*
X511653Y67927D01*
X511853Y67261D01*
Y63394D01*
G01Y67261D02*
X512053Y67927D01*
X512386Y68461D01*
X512853Y68727D01*
X513320Y68461D01*
X513653Y67927D01*
X513853Y67127D01*
Y63394D01*
G01D02*
Y68727D01*
G01Y67261D02*
X514053Y67927D01*
X514386Y68461D01*
X514853Y68727D01*
X515320Y68461D01*
X515653Y67927D01*
X515853Y67261D01*
Y63394D01*
G01Y67261D02*
X516053Y67927D01*
X516386Y68461D01*
X516853Y68727D01*
X517320Y68461D01*
X517653Y67927D01*
X517853Y67127D01*
Y63394D01*
G01X523853Y71394D02*
Y63394D01*
G01X522920Y68727D02*
X524786D01*
G01X527853Y63394D02*
X527453Y63527D01*
X527053Y64061D01*
X526786Y64994D01*
X526653Y66061D01*
X526786Y67127D01*
X527053Y68061D01*
X527453Y68594D01*
X527853Y68727D01*
X528253Y68594D01*
X528653Y68061D01*
X528920Y67127D01*
X528986Y66061D01*
X528920Y64994D01*
X528653Y64061D01*
X528253Y63527D01*
X527853Y63394D01*
G01X534653Y60727D02*
Y68727D01*
G01Y67527D02*
X534986Y68194D01*
X535320Y68594D01*
X535853Y68727D01*
X536320Y68594D01*
X536786Y67927D01*
X536986Y66994D01*
X537053Y66061D01*
X536986Y65127D01*
X536786Y64194D01*
X536386Y63661D01*
X535853Y63394D01*
X535386Y63527D01*
X534920Y63927D01*
X534653Y64460D01*
G01X538920Y63394D02*
Y68727D01*
G01Y67661D02*
X539253Y68194D01*
X539586Y68594D01*
X540053Y68727D01*
X540386Y68594D01*
X540786Y68194D01*
G01X543853Y63394D02*
X543453Y63527D01*
X543053Y64061D01*
X542786Y64994D01*
X542653Y66061D01*
X542786Y67127D01*
X543053Y68061D01*
X543453Y68594D01*
X543853Y68727D01*
X544253Y68594D01*
X544653Y68061D01*
X544920Y67127D01*
X544986Y66061D01*
X544920Y64994D01*
X544653Y64061D01*
X544253Y63527D01*
X543853Y63394D01*
G01X549053Y71394D02*
Y63394D01*
G01Y64594D02*
X548786Y63927D01*
X548386Y63527D01*
X547920Y63394D01*
X547386Y63661D01*
X546986Y64327D01*
X546720Y65127D01*
X546653Y66061D01*
X546720Y66994D01*
X546986Y67794D01*
X547386Y68461D01*
X547920Y68727D01*
X548386Y68594D01*
X548720Y68327D01*
X549053Y67794D01*
G01X550720Y68727D02*
Y64994D01*
X550986Y64061D01*
X551386Y63527D01*
X551853Y63394D01*
X552320Y63527D01*
X552720Y64061D01*
X552986Y64994D01*
G01Y63394D02*
Y68727D01*
G01X556920Y68061D02*
X556453Y68594D01*
X556053Y68727D01*
X555520Y68461D01*
X555120Y67927D01*
X554853Y66994D01*
X554786Y66061D01*
X554853Y65127D01*
X555120Y64327D01*
X555520Y63661D01*
X556053Y63394D01*
X556520Y63661D01*
X556920Y64194D01*
G01X558853Y66994D02*
X560986D01*
X560786Y67927D01*
X560453Y68461D01*
X559986Y68727D01*
X559520Y68594D01*
X559120Y68194D01*
X558853Y67261D01*
X558720Y66460D01*
Y65661D01*
X558853Y64861D01*
X559186Y64061D01*
X559586Y63527D01*
X560053Y63394D01*
X560520Y63661D01*
X560986Y64460D01*
G01X567853Y71394D02*
Y63394D01*
G01X566920Y68727D02*
X568786D01*
G01X570720Y63394D02*
Y71394D01*
G01Y67527D02*
X571053Y68194D01*
X571386Y68594D01*
X571920Y68727D01*
X572320Y68594D01*
X572786Y68061D01*
X572986Y67261D01*
Y63394D01*
G01X575853Y68727D02*
Y63394D01*
G01Y70861D02*
X575720Y70994D01*
Y71261D01*
X575853Y71394D01*
X575986Y71261D01*
Y70994D01*
X575853Y70861D01*
G01X578853Y64327D02*
X579186Y63794D01*
X579653Y63394D01*
X580053D01*
X580453Y63661D01*
X580720Y64061D01*
X580853Y64594D01*
X580786Y65394D01*
X580520Y65794D01*
X579320Y66594D01*
X579053Y67527D01*
X579186Y68194D01*
X579453Y68594D01*
X579853Y68727D01*
X580253Y68594D01*
X580653Y68194D01*
G01X586653Y63394D02*
Y71394D01*
G01Y67394D02*
X586986Y68194D01*
X587386Y68594D01*
X587786Y68727D01*
X588386Y68461D01*
X588786Y67927D01*
X589053Y66994D01*
Y65927D01*
X588920Y64861D01*
X588653Y64061D01*
X588186Y63527D01*
X587786Y63394D01*
X587386Y63527D01*
X586986Y63927D01*
X586653Y64594D01*
G01X591853Y63394D02*
X591453Y63527D01*
X591053Y64061D01*
X590786Y64994D01*
X590653Y66061D01*
X590786Y67127D01*
X591053Y68061D01*
X591453Y68594D01*
X591853Y68727D01*
X592253Y68594D01*
X592653Y68061D01*
X592920Y67127D01*
X592986Y66061D01*
X592920Y64994D01*
X592653Y64061D01*
X592253Y63527D01*
X591853Y63394D01*
G01X597053D02*
Y68727D01*
G01Y67794D02*
X596786Y68327D01*
X596386Y68594D01*
X595920Y68727D01*
X595453Y68461D01*
X595053Y67927D01*
X594786Y67127D01*
X594653Y66061D01*
X594786Y64994D01*
X595053Y64194D01*
X595453Y63661D01*
X595920Y63394D01*
X596386Y63527D01*
X596786Y63927D01*
X597053Y64460D01*
G01X598920Y63394D02*
Y68727D01*
G01Y67661D02*
X599253Y68194D01*
X599586Y68594D01*
X600053Y68727D01*
X600386Y68594D01*
X600786Y68194D01*
G01X605053Y71394D02*
Y63394D01*
G01Y64594D02*
X604786Y63927D01*
X604386Y63527D01*
X603920Y63394D01*
X603386Y63661D01*
X602986Y64327D01*
X602720Y65127D01*
X602653Y66061D01*
X602720Y66994D01*
X602986Y67794D01*
X603386Y68461D01*
X603920Y68727D01*
X604386Y68594D01*
X604720Y68327D01*
X605053Y67794D01*
G01X607853Y63127D02*
X607720Y63261D01*
Y63527D01*
X607853Y63661D01*
X607986Y63527D01*
Y63261D01*
X607853Y63127D01*
G01X395653Y81394D02*
Y73394D01*
G01X394120Y81394D02*
X397186D01*
G01X398520Y73394D02*
Y81394D01*
G01Y77527D02*
X398853Y78194D01*
X399186Y78594D01*
X399720Y78727D01*
X400120Y78594D01*
X400586Y78061D01*
X400786Y77261D01*
Y73394D01*
G01X402653Y76994D02*
X404786D01*
X404586Y77927D01*
X404253Y78461D01*
X403786Y78727D01*
X403320Y78594D01*
X402920Y78194D01*
X402653Y77261D01*
X402520Y76460D01*
Y75661D01*
X402653Y74861D01*
X402986Y74061D01*
X403386Y73527D01*
X403853Y73394D01*
X404320Y73661D01*
X404786Y74460D01*
G01X406520Y73394D02*
Y78727D01*
G01Y77394D02*
X406786Y78061D01*
X407186Y78594D01*
X407720Y78727D01*
X408186Y78594D01*
X408586Y78061D01*
X408786Y77127D01*
Y73394D01*
G01X416720Y78061D02*
X416253Y78594D01*
X415853Y78727D01*
X415320Y78461D01*
X414920Y77927D01*
X414653Y76994D01*
X414586Y76061D01*
X414653Y75127D01*
X414920Y74327D01*
X415320Y73661D01*
X415853Y73394D01*
X416320Y73661D01*
X416720Y74194D01*
G01X419653Y73394D02*
X419253Y73527D01*
X418853Y74061D01*
X418586Y74994D01*
X418453Y76061D01*
X418586Y77127D01*
X418853Y78061D01*
X419253Y78594D01*
X419653Y78727D01*
X420053Y78594D01*
X420453Y78061D01*
X420720Y77127D01*
X420786Y76061D01*
X420720Y74994D01*
X420453Y74061D01*
X420053Y73527D01*
X419653Y73394D01*
G01X422520D02*
Y78727D01*
G01Y77394D02*
X422786Y78061D01*
X423186Y78594D01*
X423720Y78727D01*
X424186Y78594D01*
X424586Y78061D01*
X424786Y77127D01*
Y73394D01*
G01X426453Y78727D02*
X427653Y73394D01*
X428853Y78727D01*
G01X430653Y76994D02*
X432786D01*
X432586Y77927D01*
X432253Y78461D01*
X431786Y78727D01*
X431320Y78594D01*
X430920Y78194D01*
X430653Y77261D01*
X430520Y76460D01*
Y75661D01*
X430653Y74861D01*
X430986Y74061D01*
X431386Y73527D01*
X431853Y73394D01*
X432320Y73661D01*
X432786Y74460D01*
G01X434720Y73394D02*
Y78727D01*
G01Y77661D02*
X435053Y78194D01*
X435386Y78594D01*
X435853Y78727D01*
X436186Y78594D01*
X436586Y78194D01*
G01X439653Y81394D02*
Y73394D01*
G01X438720Y78727D02*
X440586D01*
G01X446186Y74994D02*
X446586Y74061D01*
X447120Y73527D01*
X447720Y73394D01*
X448253Y73527D01*
X448786Y74194D01*
X449120Y74994D01*
X449186Y75794D01*
X449053Y76727D01*
X448586Y77394D01*
X448120Y77661D01*
X447520D01*
G01X448120D02*
X448520Y78061D01*
X448853Y78727D01*
X448986Y79527D01*
X448853Y80327D01*
X448520Y80994D01*
X447920Y81394D01*
X447320Y81261D01*
X446720Y80727D01*
G01X451653Y73127D02*
X451520Y73261D01*
Y73527D01*
X451653Y73661D01*
X451786Y73527D01*
Y73261D01*
X451653Y73127D01*
G01X455653Y73394D02*
Y81394D01*
X454853Y79794D01*
G01Y73394D02*
X456453D01*
G01X459653D02*
X460120Y73527D01*
X460653Y73927D01*
X460986Y74594D01*
X461120Y75527D01*
X460986Y76460D01*
X460586Y77261D01*
X459986Y77661D01*
X459320D01*
X458920Y77927D01*
X458586Y78594D01*
X458453Y79527D01*
X458653Y80461D01*
X459120Y81127D01*
X459653Y81394D01*
X460186Y81127D01*
X460653Y80461D01*
X460853Y79527D01*
X460720Y78594D01*
X460386Y77927D01*
X459986Y77661D01*
X459320D01*
X458720Y77261D01*
X458320Y76460D01*
X458186Y75527D01*
X458320Y74594D01*
X458653Y73927D01*
X459186Y73527D01*
X459653Y73394D01*
G01X461653D02*
Y78727D01*
G01Y77261D02*
X461853Y77927D01*
X462186Y78461D01*
X462653Y78727D01*
X463120Y78461D01*
X463453Y77927D01*
X463653Y77261D01*
Y73394D01*
G01Y77261D02*
X463853Y77927D01*
X464186Y78461D01*
X464653Y78727D01*
X465120Y78461D01*
X465453Y77927D01*
X465653Y77127D01*
Y73394D01*
G01D02*
Y78727D01*
G01Y77261D02*
X465853Y77927D01*
X466186Y78461D01*
X466653Y78727D01*
X467120Y78461D01*
X467453Y77927D01*
X467653Y77261D01*
Y73394D01*
G01Y77261D02*
X467853Y77927D01*
X468186Y78461D01*
X468653Y78727D01*
X469120Y78461D01*
X469453Y77927D01*
X469653Y77127D01*
Y73394D01*
G01X475653Y78727D02*
Y73394D01*
G01Y80861D02*
X475520Y80994D01*
Y81261D01*
X475653Y81394D01*
X475786Y81261D01*
Y80994D01*
X475653Y80861D01*
G01X478520Y73394D02*
Y78727D01*
G01Y77394D02*
X478786Y78061D01*
X479186Y78594D01*
X479720Y78727D01*
X480186Y78594D01*
X480586Y78061D01*
X480786Y77127D01*
Y73394D01*
G01X483653Y81394D02*
Y73394D01*
G01X482720Y78727D02*
X484586D01*
G01X487653Y73394D02*
X487253Y73527D01*
X486853Y74061D01*
X486586Y74994D01*
X486453Y76061D01*
X486586Y77127D01*
X486853Y78061D01*
X487253Y78594D01*
X487653Y78727D01*
X488053Y78594D01*
X488453Y78061D01*
X488720Y77127D01*
X488786Y76061D01*
X488720Y74994D01*
X488453Y74061D01*
X488053Y73527D01*
X487653Y73394D01*
G01X495653D02*
Y81394D01*
X494853Y79794D01*
G01Y73394D02*
X496453D01*
G01X498386Y80061D02*
X498786Y80861D01*
X499253Y81261D01*
X499786Y81394D01*
X500453Y81127D01*
X500920Y80461D01*
X501053Y79661D01*
X500986Y78860D01*
X500720Y78194D01*
X499386Y76861D01*
X498786Y75927D01*
X498386Y74594D01*
X498253Y73394D01*
X501053D01*
G01X502186Y74594D02*
X502586Y73927D01*
X503053Y73527D01*
X503653Y73394D01*
X504253Y73661D01*
X504720Y74194D01*
X505053Y75127D01*
X505120Y76194D01*
X504986Y77261D01*
X504653Y77927D01*
X504186Y78461D01*
X503720Y78594D01*
X503253Y78461D01*
X502653Y77927D01*
X502853Y81394D01*
X504653D01*
G01X507653Y73127D02*
X507520Y73261D01*
Y73527D01*
X507653Y73661D01*
X507786Y73527D01*
Y73261D01*
X507653Y73127D01*
G01X511653Y73394D02*
Y81394D01*
X510853Y79794D01*
G01Y73394D02*
X512453D01*
G01X514520Y74327D02*
X514986Y73661D01*
X515520Y73394D01*
X516053Y73661D01*
X516520Y74460D01*
X516853Y75661D01*
X516986Y76861D01*
Y78327D01*
X516853Y79527D01*
X516520Y80594D01*
X516120Y81127D01*
X515653Y81394D01*
X515120Y81127D01*
X514720Y80594D01*
X514453Y79794D01*
X514320Y78727D01*
X514453Y77794D01*
X514786Y76861D01*
X515186Y76327D01*
X515653Y76194D01*
X516186Y76460D01*
X516586Y77127D01*
X516986Y78327D01*
G01X518386Y76727D02*
X518853Y77661D01*
X519253Y78194D01*
X519786Y78461D01*
X520253Y78194D01*
X520586Y77661D01*
X520853Y76861D01*
X520920Y75927D01*
X520853Y75127D01*
X520586Y74327D01*
X520186Y73661D01*
X519720Y73394D01*
X519186Y73661D01*
X518720Y74460D01*
X518453Y75661D01*
X518386Y76994D01*
X518520Y78727D01*
X518720Y79661D01*
X519053Y80594D01*
X519520Y81261D01*
X519986Y81394D01*
X520453Y81127D01*
X520786Y80461D01*
G01X523653Y73394D02*
X524120Y73527D01*
X524653Y73927D01*
X524986Y74594D01*
X525120Y75527D01*
X524986Y76460D01*
X524586Y77261D01*
X523986Y77661D01*
X523320D01*
X522920Y77927D01*
X522586Y78594D01*
X522453Y79527D01*
X522653Y80461D01*
X523120Y81127D01*
X523653Y81394D01*
X524186Y81127D01*
X524653Y80461D01*
X524853Y79527D01*
X524720Y78594D01*
X524386Y77927D01*
X523986Y77661D01*
X523320D01*
X522720Y77261D01*
X522320Y76460D01*
X522186Y75527D01*
X522320Y74594D01*
X522653Y73927D01*
X523186Y73527D01*
X523653Y73394D01*
G01X525653D02*
Y78727D01*
G01Y77261D02*
X525853Y77927D01*
X526186Y78461D01*
X526653Y78727D01*
X527120Y78461D01*
X527453Y77927D01*
X527653Y77261D01*
Y73394D01*
G01Y77261D02*
X527853Y77927D01*
X528186Y78461D01*
X528653Y78727D01*
X529120Y78461D01*
X529453Y77927D01*
X529653Y77127D01*
Y73394D01*
G01X531653Y78727D02*
Y73394D01*
G01Y80861D02*
X531520Y80994D01*
Y81261D01*
X531653Y81394D01*
X531786Y81261D01*
Y80994D01*
X531653Y80861D01*
G01X535653Y73394D02*
Y81394D01*
G01X539520Y71927D02*
X539786Y73661D01*
G01X547653Y81394D02*
Y73394D01*
G01X546720Y78727D02*
X548586D01*
G01X550520Y73394D02*
Y81394D01*
G01Y77527D02*
X550853Y78194D01*
X551186Y78594D01*
X551720Y78727D01*
X552120Y78594D01*
X552586Y78061D01*
X552786Y77261D01*
Y73394D01*
G01X554653Y76994D02*
X556786D01*
X556586Y77927D01*
X556253Y78461D01*
X555786Y78727D01*
X555320Y78594D01*
X554920Y78194D01*
X554653Y77261D01*
X554520Y76460D01*
Y75661D01*
X554653Y74861D01*
X554986Y74061D01*
X555386Y73527D01*
X555853Y73394D01*
X556320Y73661D01*
X556786Y74460D01*
G01X564853Y81394D02*
Y73394D01*
G01Y74594D02*
X564586Y73927D01*
X564186Y73527D01*
X563720Y73394D01*
X563186Y73661D01*
X562786Y74327D01*
X562520Y75127D01*
X562453Y76061D01*
X562520Y76994D01*
X562786Y77794D01*
X563186Y78461D01*
X563720Y78727D01*
X564186Y78594D01*
X564520Y78327D01*
X564853Y77794D01*
G01X567653Y78727D02*
Y73394D01*
G01Y80861D02*
X567520Y80994D01*
Y81261D01*
X567653Y81394D01*
X567786Y81261D01*
Y80994D01*
X567653Y80861D01*
G01X571253Y73394D02*
Y80194D01*
X571386Y80861D01*
X571653Y81261D01*
X572053Y81394D01*
X572453Y81127D01*
X572653Y80461D01*
G01X571853Y78194D02*
X570520D01*
G01X575253Y73394D02*
Y80194D01*
X575386Y80861D01*
X575653Y81261D01*
X576053Y81394D01*
X576453Y81127D01*
X576653Y80461D01*
G01X575853Y78194D02*
X574520D01*
G01X578653Y76994D02*
X580786D01*
X580586Y77927D01*
X580253Y78461D01*
X579786Y78727D01*
X579320Y78594D01*
X578920Y78194D01*
X578653Y77261D01*
X578520Y76460D01*
Y75661D01*
X578653Y74861D01*
X578986Y74061D01*
X579386Y73527D01*
X579853Y73394D01*
X580320Y73661D01*
X580786Y74460D01*
G01X582720Y73394D02*
Y78727D01*
G01Y77661D02*
X583053Y78194D01*
X583386Y78594D01*
X583853Y78727D01*
X584186Y78594D01*
X584586Y78194D01*
G01X586653Y76994D02*
X588786D01*
X588586Y77927D01*
X588253Y78461D01*
X587786Y78727D01*
X587320Y78594D01*
X586920Y78194D01*
X586653Y77261D01*
X586520Y76460D01*
Y75661D01*
X586653Y74861D01*
X586986Y74061D01*
X587386Y73527D01*
X587853Y73394D01*
X588320Y73661D01*
X588786Y74460D01*
G01X590520Y73394D02*
Y78727D01*
G01Y77394D02*
X590786Y78061D01*
X591186Y78594D01*
X591720Y78727D01*
X592186Y78594D01*
X592586Y78061D01*
X592786Y77127D01*
Y73394D01*
G01X596720Y78061D02*
X596253Y78594D01*
X595853Y78727D01*
X595320Y78461D01*
X594920Y77927D01*
X594653Y76994D01*
X594586Y76061D01*
X594653Y75127D01*
X594920Y74327D01*
X595320Y73661D01*
X595853Y73394D01*
X596320Y73661D01*
X596720Y74194D01*
G01X598653Y76994D02*
X600786D01*
X600586Y77927D01*
X600253Y78461D01*
X599786Y78727D01*
X599320Y78594D01*
X598920Y78194D01*
X598653Y77261D01*
X598520Y76460D01*
Y75661D01*
X598653Y74861D01*
X598986Y74061D01*
X599386Y73527D01*
X599853Y73394D01*
X600320Y73661D01*
X600786Y74460D01*
G01X606453Y73394D02*
Y81394D01*
G01Y77394D02*
X606786Y78194D01*
X607186Y78594D01*
X607586Y78727D01*
X608186Y78461D01*
X608586Y77927D01*
X608853Y76994D01*
Y75927D01*
X608720Y74861D01*
X608453Y74061D01*
X607986Y73527D01*
X607586Y73394D01*
X607186Y73527D01*
X606786Y73927D01*
X606453Y74594D01*
G01X610653Y76994D02*
X612786D01*
X612586Y77927D01*
X612253Y78461D01*
X611786Y78727D01*
X611320Y78594D01*
X610920Y78194D01*
X610653Y77261D01*
X610520Y76460D01*
Y75661D01*
X610653Y74861D01*
X610986Y74061D01*
X611386Y73527D01*
X611853Y73394D01*
X612320Y73661D01*
X612786Y74460D01*
G01X615653Y81394D02*
Y73394D01*
G01X614720Y78727D02*
X616586D01*
G01X617986D02*
X618786Y73394D01*
X619653Y78727D01*
X620520Y73394D01*
X621320Y78727D01*
G01X622653Y76994D02*
X624786D01*
X624586Y77927D01*
X624253Y78461D01*
X623786Y78727D01*
X623320Y78594D01*
X622920Y78194D01*
X622653Y77261D01*
X622520Y76460D01*
Y75661D01*
X622653Y74861D01*
X622986Y74061D01*
X623386Y73527D01*
X623853Y73394D01*
X624320Y73661D01*
X624786Y74460D01*
G01X626653Y76994D02*
X628786D01*
X628586Y77927D01*
X628253Y78461D01*
X627786Y78727D01*
X627320Y78594D01*
X626920Y78194D01*
X626653Y77261D01*
X626520Y76460D01*
Y75661D01*
X626653Y74861D01*
X626986Y74061D01*
X627386Y73527D01*
X627853Y73394D01*
X628320Y73661D01*
X628786Y74460D01*
G01X630520Y73394D02*
Y78727D01*
G01Y77394D02*
X630786Y78061D01*
X631186Y78594D01*
X631720Y78727D01*
X632186Y78594D01*
X632586Y78061D01*
X632786Y77127D01*
Y73394D01*
G01X639653D02*
Y81394D01*
X638853Y79794D01*
G01Y73394D02*
X640453D01*
G01X642386Y80061D02*
X642786Y80861D01*
X643253Y81261D01*
X643786Y81394D01*
X644453Y81127D01*
X644920Y80461D01*
X645053Y79661D01*
X644986Y78860D01*
X644720Y78194D01*
X643386Y76861D01*
X642786Y75927D01*
X642386Y74594D01*
X642253Y73394D01*
X645053D01*
G01X646386Y76727D02*
X646853Y77661D01*
X647253Y78194D01*
X647786Y78461D01*
X648253Y78194D01*
X648586Y77661D01*
X648853Y76861D01*
X648920Y75927D01*
X648853Y75127D01*
X648586Y74327D01*
X648186Y73661D01*
X647720Y73394D01*
X647186Y73661D01*
X646720Y74460D01*
X646453Y75661D01*
X646386Y76994D01*
X646520Y78727D01*
X646720Y79661D01*
X647053Y80594D01*
X647520Y81261D01*
X647986Y81394D01*
X648453Y81127D01*
X648786Y80461D01*
G01X649653Y73394D02*
Y78727D01*
G01Y77261D02*
X649853Y77927D01*
X650186Y78461D01*
X650653Y78727D01*
X651120Y78461D01*
X651453Y77927D01*
X651653Y77261D01*
Y73394D01*
G01Y77261D02*
X651853Y77927D01*
X652186Y78461D01*
X652653Y78727D01*
X653120Y78461D01*
X653453Y77927D01*
X653653Y77127D01*
Y73394D01*
G01X655653Y78727D02*
Y73394D01*
G01Y80861D02*
X655520Y80994D01*
Y81261D01*
X655653Y81394D01*
X655786Y81261D01*
Y80994D01*
X655653Y80861D01*
G01X659653Y73394D02*
Y81394D01*
G01X668853Y73394D02*
Y78727D01*
G01Y77794D02*
X668586Y78327D01*
X668186Y78594D01*
X667720Y78727D01*
X667253Y78461D01*
X666853Y77927D01*
X666586Y77127D01*
X666453Y76061D01*
X666586Y74994D01*
X666853Y74194D01*
X667253Y73661D01*
X667720Y73394D01*
X668186Y73527D01*
X668586Y73927D01*
X668853Y74460D01*
G01X670520Y73394D02*
Y78727D01*
G01Y77394D02*
X670786Y78061D01*
X671186Y78594D01*
X671720Y78727D01*
X672186Y78594D01*
X672586Y78061D01*
X672786Y77127D01*
Y73394D01*
G01X676853Y81394D02*
Y73394D01*
G01Y74594D02*
X676586Y73927D01*
X676186Y73527D01*
X675720Y73394D01*
X675186Y73661D01*
X674786Y74327D01*
X674520Y75127D01*
X674453Y76061D01*
X674520Y76994D01*
X674786Y77794D01*
X675186Y78461D01*
X675720Y78727D01*
X676186Y78594D01*
X676520Y78327D01*
X676853Y77794D01*
G01X683653Y73394D02*
Y81394D01*
X682853Y79794D01*
G01Y73394D02*
X684453D01*
G01X686386Y80061D02*
X686786Y80861D01*
X687253Y81261D01*
X687786Y81394D01*
X688453Y81127D01*
X688920Y80461D01*
X689053Y79661D01*
X688986Y78860D01*
X688720Y78194D01*
X687386Y76861D01*
X686786Y75927D01*
X686386Y74594D01*
X686253Y73394D01*
X689053D01*
G01X690186Y74594D02*
X690586Y73927D01*
X691053Y73527D01*
X691653Y73394D01*
X692253Y73661D01*
X692720Y74194D01*
X693053Y75127D01*
X693120Y76194D01*
X692986Y77261D01*
X692653Y77927D01*
X692186Y78461D01*
X691720Y78594D01*
X691253Y78461D01*
X690653Y77927D01*
X690853Y81394D01*
X692653D01*
G01X695653Y73127D02*
X695520Y73261D01*
Y73527D01*
X695653Y73661D01*
X695786Y73527D01*
Y73261D01*
X695653Y73127D01*
G01X699653Y73394D02*
Y81394D01*
X698853Y79794D01*
G01Y73394D02*
X700453D01*
G01X702520Y74327D02*
X702986Y73661D01*
X703520Y73394D01*
X704053Y73661D01*
X704520Y74460D01*
X704853Y75661D01*
X704986Y76861D01*
Y78327D01*
X704853Y79527D01*
X704520Y80594D01*
X704120Y81127D01*
X703653Y81394D01*
X703120Y81127D01*
X702720Y80594D01*
X702453Y79794D01*
X702320Y78727D01*
X702453Y77794D01*
X702786Y76861D01*
X703186Y76327D01*
X703653Y76194D01*
X704186Y76460D01*
X704586Y77127D01*
X704986Y78327D01*
G01X706386Y76727D02*
X706853Y77661D01*
X707253Y78194D01*
X707786Y78461D01*
X708253Y78194D01*
X708586Y77661D01*
X708853Y76861D01*
X708920Y75927D01*
X708853Y75127D01*
X708586Y74327D01*
X708186Y73661D01*
X707720Y73394D01*
X707186Y73661D01*
X706720Y74460D01*
X706453Y75661D01*
X706386Y76994D01*
X706520Y78727D01*
X706720Y79661D01*
X707053Y80594D01*
X707520Y81261D01*
X707986Y81394D01*
X708453Y81127D01*
X708786Y80461D01*
G01X711653Y73394D02*
X712120Y73527D01*
X712653Y73927D01*
X712986Y74594D01*
X713120Y75527D01*
X712986Y76460D01*
X712586Y77261D01*
X711986Y77661D01*
X711320D01*
X710920Y77927D01*
X710586Y78594D01*
X710453Y79527D01*
X710653Y80461D01*
X711120Y81127D01*
X711653Y81394D01*
X712186Y81127D01*
X712653Y80461D01*
X712853Y79527D01*
X712720Y78594D01*
X712386Y77927D01*
X711986Y77661D01*
X711320D01*
X710720Y77261D01*
X710320Y76460D01*
X710186Y75527D01*
X710320Y74594D01*
X710653Y73927D01*
X711186Y73527D01*
X711653Y73394D01*
G01X719653Y78727D02*
Y73394D01*
G01Y80861D02*
X719520Y80994D01*
Y81261D01*
X719653Y81394D01*
X719786Y81261D01*
Y80994D01*
X719653Y80861D01*
G01X722653Y74327D02*
X722986Y73794D01*
X723453Y73394D01*
X723853D01*
X724253Y73661D01*
X724520Y74061D01*
X724653Y74594D01*
X724586Y75394D01*
X724320Y75794D01*
X723120Y76594D01*
X722853Y77527D01*
X722986Y78194D01*
X723253Y78594D01*
X723653Y78727D01*
X724053Y78594D01*
X724453Y78194D01*
G01X731653Y73394D02*
Y81394D01*
G01X734653Y76994D02*
X736786D01*
X736586Y77927D01*
X736253Y78461D01*
X735786Y78727D01*
X735320Y78594D01*
X734920Y78194D01*
X734653Y77261D01*
X734520Y76460D01*
Y75661D01*
X734653Y74861D01*
X734986Y74061D01*
X735386Y73527D01*
X735853Y73394D01*
X736320Y73661D01*
X736786Y74460D01*
G01X738653Y74327D02*
X738986Y73794D01*
X739453Y73394D01*
X739853D01*
X740253Y73661D01*
X740520Y74061D01*
X740653Y74594D01*
X740586Y75394D01*
X740320Y75794D01*
X739120Y76594D01*
X738853Y77527D01*
X738986Y78194D01*
X739253Y78594D01*
X739653Y78727D01*
X740053Y78594D01*
X740453Y78194D01*
G01X742653Y74327D02*
X742986Y73794D01*
X743453Y73394D01*
X743853D01*
X744253Y73661D01*
X744520Y74061D01*
X744653Y74594D01*
X744586Y75394D01*
X744320Y75794D01*
X743120Y76594D01*
X742853Y77527D01*
X742986Y78194D01*
X743253Y78594D01*
X743653Y78727D01*
X744053Y78594D01*
X744453Y78194D01*
G01X751653Y81394D02*
Y73394D01*
G01X750720Y78727D02*
X752586D01*
G01X754520Y73394D02*
Y81394D01*
G01Y77527D02*
X754853Y78194D01*
X755186Y78594D01*
X755720Y78727D01*
X756120Y78594D01*
X756586Y78061D01*
X756786Y77261D01*
Y73394D01*
G01X760853D02*
Y78727D01*
G01Y77794D02*
X760586Y78327D01*
X760186Y78594D01*
X759720Y78727D01*
X759253Y78461D01*
X758853Y77927D01*
X758586Y77127D01*
X758453Y76061D01*
X758586Y74994D01*
X758853Y74194D01*
X759253Y73661D01*
X759720Y73394D01*
X760186Y73527D01*
X760586Y73927D01*
X760853Y74460D01*
G01X762520Y73394D02*
Y78727D01*
G01Y77394D02*
X762786Y78061D01*
X763186Y78594D01*
X763720Y78727D01*
X764186Y78594D01*
X764586Y78061D01*
X764786Y77127D01*
Y73394D01*
G01X771653D02*
Y81394D01*
X770853Y79794D01*
G01Y73394D02*
X772453D01*
G01X777653D02*
Y78727D01*
G01Y77261D02*
X777853Y77927D01*
X778186Y78461D01*
X778653Y78727D01*
X779120Y78461D01*
X779453Y77927D01*
X779653Y77261D01*
Y73394D01*
G01Y77261D02*
X779853Y77927D01*
X780186Y78461D01*
X780653Y78727D01*
X781120Y78461D01*
X781453Y77927D01*
X781653Y77127D01*
Y73394D01*
G01X783653Y78727D02*
Y73394D01*
G01Y80861D02*
X783520Y80994D01*
Y81261D01*
X783653Y81394D01*
X783786Y81261D01*
Y80994D01*
X783653Y80861D01*
G01X787653Y73394D02*
Y81394D01*
G01X791520Y71927D02*
X791786Y73661D01*
G01X381820Y161794D02*
Y169794D01*
X383486D01*
X384020Y169394D01*
X384353Y168861D01*
X384486Y167794D01*
X384353Y166727D01*
X383953Y166061D01*
X383486Y165661D01*
X381820D01*
G01X383486D02*
X384486Y161794D01*
G01X387153D02*
X386753Y161927D01*
X386353Y162461D01*
X386086Y163394D01*
X385953Y164461D01*
X386086Y165527D01*
X386353Y166461D01*
X386753Y166994D01*
X387153Y167127D01*
X387553Y166994D01*
X387953Y166461D01*
X388220Y165527D01*
X388286Y164461D01*
X388220Y163394D01*
X387953Y162461D01*
X387553Y161927D01*
X387153Y161794D01*
G01X390020Y167127D02*
Y163394D01*
X390286Y162461D01*
X390686Y161927D01*
X391153Y161794D01*
X391620Y161927D01*
X392020Y162461D01*
X392286Y163394D01*
G01Y161794D02*
Y167127D01*
G01X394220Y159794D02*
X394686Y159261D01*
X395220Y159127D01*
X395686Y159261D01*
X396086Y159927D01*
X396353Y160861D01*
Y167127D01*
G01Y166061D02*
X396086Y166594D01*
X395686Y166994D01*
X395220Y167127D01*
X394686Y166861D01*
X394353Y166327D01*
X394086Y165394D01*
X393953Y164461D01*
X394020Y163661D01*
X394286Y162727D01*
X394686Y162061D01*
X395220Y161794D01*
X395620Y161927D01*
X396086Y162461D01*
X396353Y162994D01*
G01X398020Y161794D02*
Y169794D01*
G01Y165927D02*
X398353Y166594D01*
X398686Y166994D01*
X399220Y167127D01*
X399620Y166994D01*
X400086Y166461D01*
X400286Y165661D01*
Y161794D01*
G01X402020D02*
Y167127D01*
G01Y165794D02*
X402286Y166461D01*
X402686Y166994D01*
X403220Y167127D01*
X403686Y166994D01*
X404086Y166461D01*
X404286Y165527D01*
Y161794D01*
G01X406153Y165394D02*
X408286D01*
X408086Y166327D01*
X407753Y166861D01*
X407286Y167127D01*
X406820Y166994D01*
X406420Y166594D01*
X406153Y165661D01*
X406020Y164860D01*
Y164061D01*
X406153Y163261D01*
X406486Y162461D01*
X406886Y161927D01*
X407353Y161794D01*
X407820Y162061D01*
X408286Y162860D01*
G01X410153Y162727D02*
X410486Y162194D01*
X410953Y161794D01*
X411353D01*
X411753Y162061D01*
X412020Y162461D01*
X412153Y162994D01*
X412086Y163794D01*
X411820Y164194D01*
X410620Y164994D01*
X410353Y165927D01*
X410486Y166594D01*
X410753Y166994D01*
X411153Y167127D01*
X411553Y166994D01*
X411953Y166594D01*
G01X414153Y162727D02*
X414486Y162194D01*
X414953Y161794D01*
X415353D01*
X415753Y162061D01*
X416020Y162461D01*
X416153Y162994D01*
X416086Y163794D01*
X415820Y164194D01*
X414620Y164994D01*
X414353Y165927D01*
X414486Y166594D01*
X414753Y166994D01*
X415153Y167127D01*
X415553Y166994D01*
X415953Y166594D01*
G01X378253Y253794D02*
Y261794D01*
G01X381053D02*
Y253794D01*
G01Y257794D02*
X378253D01*
G01X383653Y253794D02*
X383253Y253927D01*
X382853Y254461D01*
X382586Y255394D01*
X382453Y256461D01*
X382586Y257527D01*
X382853Y258461D01*
X383253Y258994D01*
X383653Y259127D01*
X384053Y258994D01*
X384453Y258461D01*
X384720Y257527D01*
X384786Y256461D01*
X384720Y255394D01*
X384453Y254461D01*
X384053Y253927D01*
X383653Y253794D01*
G01X387653D02*
Y261794D01*
G01X390653Y257394D02*
X392786D01*
X392586Y258327D01*
X392253Y258861D01*
X391786Y259127D01*
X391320Y258994D01*
X390920Y258594D01*
X390653Y257661D01*
X390520Y256860D01*
Y256061D01*
X390653Y255261D01*
X390986Y254461D01*
X391386Y253927D01*
X391853Y253794D01*
X392320Y254061D01*
X392786Y254860D01*
G01X421253D02*
X421786Y254194D01*
X422386Y253794D01*
X422920D01*
X423453Y254194D01*
X423853Y254860D01*
X424053Y255794D01*
X423920Y256727D01*
X423586Y257527D01*
X422986Y258061D01*
X422186Y258327D01*
X421720Y258861D01*
X421520Y259794D01*
X421653Y260727D01*
X421986Y261394D01*
X422453Y261794D01*
X422920D01*
X423386Y261527D01*
X423786Y260861D01*
G01X426653Y259127D02*
Y253794D01*
G01Y261261D02*
X426520Y261394D01*
Y261661D01*
X426653Y261794D01*
X426786Y261661D01*
Y261394D01*
X426653Y261261D01*
G01X429653Y259127D02*
X431653D01*
X429653Y253794D01*
X431653D01*
G01X433653Y257394D02*
X435786D01*
X435586Y258327D01*
X435253Y258861D01*
X434786Y259127D01*
X434320Y258994D01*
X433920Y258594D01*
X433653Y257661D01*
X433520Y256860D01*
Y256061D01*
X433653Y255261D01*
X433986Y254461D01*
X434386Y253927D01*
X434853Y253794D01*
X435320Y254061D01*
X435786Y254860D01*
G01X366253Y311294D02*
Y319294D01*
G01X369053D02*
Y311294D01*
G01Y315294D02*
X366253D01*
G01X371653Y311294D02*
X371253Y311427D01*
X370853Y311961D01*
X370586Y312894D01*
X370453Y313961D01*
X370586Y315027D01*
X370853Y315961D01*
X371253Y316494D01*
X371653Y316627D01*
X372053Y316494D01*
X372453Y315961D01*
X372720Y315027D01*
X372786Y313961D01*
X372720Y312894D01*
X372453Y311961D01*
X372053Y311427D01*
X371653Y311294D01*
G01X375653D02*
Y319294D01*
G01X378653Y314894D02*
X380786D01*
X380586Y315827D01*
X380253Y316361D01*
X379786Y316627D01*
X379320Y316494D01*
X378920Y316094D01*
X378653Y315161D01*
X378520Y314360D01*
Y313561D01*
X378653Y312761D01*
X378986Y311961D01*
X379386Y311427D01*
X379853Y311294D01*
X380320Y311561D01*
X380786Y312360D01*
G01X400986Y310794D02*
X402653Y318794D01*
X404320Y310794D01*
G01X403720Y313594D02*
X401586D01*
G01X406653Y310794D02*
Y318794D01*
G01X410653Y316127D02*
Y310794D01*
G01Y318261D02*
X410520Y318394D01*
Y318661D01*
X410653Y318794D01*
X410786Y318661D01*
Y318394D01*
X410653Y318261D01*
G01X413720Y308794D02*
X414186Y308261D01*
X414720Y308127D01*
X415186Y308261D01*
X415586Y308927D01*
X415853Y309861D01*
Y316127D01*
G01Y315061D02*
X415586Y315594D01*
X415186Y315994D01*
X414720Y316127D01*
X414186Y315861D01*
X413853Y315327D01*
X413586Y314394D01*
X413453Y313461D01*
X413520Y312661D01*
X413786Y311727D01*
X414186Y311061D01*
X414720Y310794D01*
X415120Y310927D01*
X415586Y311461D01*
X415853Y311994D01*
G01X417520Y310794D02*
Y316127D01*
G01Y314794D02*
X417786Y315461D01*
X418186Y315994D01*
X418720Y316127D01*
X419186Y315994D01*
X419586Y315461D01*
X419786Y314527D01*
Y310794D01*
G01X420653D02*
Y316127D01*
G01Y314661D02*
X420853Y315327D01*
X421186Y315861D01*
X421653Y316127D01*
X422120Y315861D01*
X422453Y315327D01*
X422653Y314661D01*
Y310794D01*
G01Y314661D02*
X422853Y315327D01*
X423186Y315861D01*
X423653Y316127D01*
X424120Y315861D01*
X424453Y315327D01*
X424653Y314527D01*
Y310794D01*
G01X425653Y314394D02*
X427786D01*
X427586Y315327D01*
X427253Y315861D01*
X426786Y316127D01*
X426320Y315994D01*
X425920Y315594D01*
X425653Y314661D01*
X425520Y313860D01*
Y313061D01*
X425653Y312261D01*
X425986Y311461D01*
X426386Y310927D01*
X426853Y310794D01*
X427320Y311061D01*
X427786Y311860D01*
G01X429520Y310794D02*
Y316127D01*
G01Y314794D02*
X429786Y315461D01*
X430186Y315994D01*
X430720Y316127D01*
X431186Y315994D01*
X431586Y315461D01*
X431786Y314527D01*
Y310794D01*
G01X434653Y318794D02*
Y310794D01*
G01X433720Y316127D02*
X435586D01*
G01X483753Y162294D02*
Y170294D01*
G01X486553D02*
Y162294D01*
G01Y166294D02*
X483753D01*
G01X489153Y162294D02*
X488753Y162427D01*
X488353Y162961D01*
X488086Y163894D01*
X487953Y164961D01*
X488086Y166027D01*
X488353Y166961D01*
X488753Y167494D01*
X489153Y167627D01*
X489553Y167494D01*
X489953Y166961D01*
X490220Y166027D01*
X490286Y164961D01*
X490220Y163894D01*
X489953Y162961D01*
X489553Y162427D01*
X489153Y162294D01*
G01X493153D02*
Y170294D01*
G01X496153Y165894D02*
X498286D01*
X498086Y166827D01*
X497753Y167361D01*
X497286Y167627D01*
X496820Y167494D01*
X496420Y167094D01*
X496153Y166161D01*
X496020Y165360D01*
Y164561D01*
X496153Y163761D01*
X496486Y162961D01*
X496886Y162427D01*
X497353Y162294D01*
X497820Y162561D01*
X498286Y163360D01*
G01X503153Y170294D02*
X504086Y162294D01*
X505153Y170294D01*
X506220Y162294D01*
X507153Y170294D01*
G01X510353Y162294D02*
Y167627D01*
G01Y166694D02*
X510086Y167227D01*
X509686Y167494D01*
X509220Y167627D01*
X508753Y167361D01*
X508353Y166827D01*
X508086Y166027D01*
X507953Y164961D01*
X508086Y163894D01*
X508353Y163094D01*
X508753Y162561D01*
X509220Y162294D01*
X509686Y162427D01*
X510086Y162827D01*
X510353Y163360D01*
G01X513153Y162294D02*
Y170294D01*
G01X517153Y162294D02*
Y170294D01*
G01X523820Y162294D02*
Y170294D01*
X525486D01*
X526020Y169894D01*
X526353Y169361D01*
X526486Y168294D01*
X526353Y167227D01*
X525953Y166561D01*
X525486Y166161D01*
X523820D01*
G01X525486D02*
X526486Y162294D01*
G01X529153D02*
X528753Y162427D01*
X528353Y162961D01*
X528086Y163894D01*
X527953Y164961D01*
X528086Y166027D01*
X528353Y166961D01*
X528753Y167494D01*
X529153Y167627D01*
X529553Y167494D01*
X529953Y166961D01*
X530220Y166027D01*
X530286Y164961D01*
X530220Y163894D01*
X529953Y162961D01*
X529553Y162427D01*
X529153Y162294D01*
G01X532020Y167627D02*
Y163894D01*
X532286Y162961D01*
X532686Y162427D01*
X533153Y162294D01*
X533620Y162427D01*
X534020Y162961D01*
X534286Y163894D01*
G01Y162294D02*
Y167627D01*
G01X536220Y160294D02*
X536686Y159761D01*
X537220Y159627D01*
X537686Y159761D01*
X538086Y160427D01*
X538353Y161361D01*
Y167627D01*
G01Y166561D02*
X538086Y167094D01*
X537686Y167494D01*
X537220Y167627D01*
X536686Y167361D01*
X536353Y166827D01*
X536086Y165894D01*
X535953Y164961D01*
X536020Y164161D01*
X536286Y163227D01*
X536686Y162561D01*
X537220Y162294D01*
X537620Y162427D01*
X538086Y162961D01*
X538353Y163494D01*
G01X540020Y162294D02*
Y170294D01*
G01Y166427D02*
X540353Y167094D01*
X540686Y167494D01*
X541220Y167627D01*
X541620Y167494D01*
X542086Y166961D01*
X542286Y166161D01*
Y162294D01*
G01X544020D02*
Y167627D01*
G01Y166294D02*
X544286Y166961D01*
X544686Y167494D01*
X545220Y167627D01*
X545686Y167494D01*
X546086Y166961D01*
X546286Y166027D01*
Y162294D01*
G01X548153Y165894D02*
X550286D01*
X550086Y166827D01*
X549753Y167361D01*
X549286Y167627D01*
X548820Y167494D01*
X548420Y167094D01*
X548153Y166161D01*
X548020Y165360D01*
Y164561D01*
X548153Y163761D01*
X548486Y162961D01*
X548886Y162427D01*
X549353Y162294D01*
X549820Y162561D01*
X550286Y163360D01*
G01X552153Y163227D02*
X552486Y162694D01*
X552953Y162294D01*
X553353D01*
X553753Y162561D01*
X554020Y162961D01*
X554153Y163494D01*
X554086Y164294D01*
X553820Y164694D01*
X552620Y165494D01*
X552353Y166427D01*
X552486Y167094D01*
X552753Y167494D01*
X553153Y167627D01*
X553553Y167494D01*
X553953Y167094D01*
G01X556153Y163227D02*
X556486Y162694D01*
X556953Y162294D01*
X557353D01*
X557753Y162561D01*
X558020Y162961D01*
X558153Y163494D01*
X558086Y164294D01*
X557820Y164694D01*
X556620Y165494D01*
X556353Y166427D01*
X556486Y167094D01*
X556753Y167494D01*
X557153Y167627D01*
X557553Y167494D01*
X557953Y167094D01*
G01X484153Y174294D02*
X483620Y174427D01*
X483153Y174961D01*
X482753Y175761D01*
X482486Y176694D01*
X482353Y177761D01*
Y178827D01*
X482486Y179894D01*
X482753Y180827D01*
X483153Y181627D01*
X483620Y182161D01*
X484153Y182294D01*
X484686Y182161D01*
X485153Y181627D01*
X485553Y180827D01*
X485820Y179894D01*
X485953Y178827D01*
Y177761D01*
X485820Y176694D01*
X485553Y175761D01*
X485153Y174961D01*
X484686Y174427D01*
X484153Y174294D01*
G01X488153Y182294D02*
Y174294D01*
G01X487220Y179627D02*
X489086D01*
G01X491020Y174294D02*
Y182294D01*
G01Y178427D02*
X491353Y179094D01*
X491686Y179494D01*
X492220Y179627D01*
X492620Y179494D01*
X493086Y178961D01*
X493286Y178161D01*
Y174294D01*
G01X495153Y177894D02*
X497286D01*
X497086Y178827D01*
X496753Y179361D01*
X496286Y179627D01*
X495820Y179494D01*
X495420Y179094D01*
X495153Y178161D01*
X495020Y177360D01*
Y176561D01*
X495153Y175761D01*
X495486Y174961D01*
X495886Y174427D01*
X496353Y174294D01*
X496820Y174561D01*
X497286Y175360D01*
G01X499220Y174294D02*
Y179627D01*
G01Y178561D02*
X499553Y179094D01*
X499886Y179494D01*
X500353Y179627D01*
X500686Y179494D01*
X501086Y179094D01*
G01X503153Y175227D02*
X503486Y174694D01*
X503953Y174294D01*
X504353D01*
X504753Y174561D01*
X505020Y174961D01*
X505153Y175494D01*
X505086Y176294D01*
X504820Y176694D01*
X503620Y177494D01*
X503353Y178427D01*
X503486Y179094D01*
X503753Y179494D01*
X504153Y179627D01*
X504553Y179494D01*
X504953Y179094D01*
G01X511820Y171627D02*
X511153Y172961D01*
X510820Y174294D01*
Y179627D01*
X511153Y180961D01*
X511820Y182294D01*
G01X516153Y174294D02*
Y182294D01*
G01X520153Y179627D02*
Y174294D01*
G01Y181761D02*
X520020Y181894D01*
Y182161D01*
X520153Y182294D01*
X520286Y182161D01*
Y181894D01*
X520153Y181761D01*
G01X523020Y174294D02*
Y182294D01*
G01X525153Y179627D02*
X523020Y176561D01*
G01X523886Y177761D02*
X525286Y174294D01*
G01X527153Y177894D02*
X529286D01*
X529086Y178827D01*
X528753Y179361D01*
X528286Y179627D01*
X527820Y179494D01*
X527420Y179094D01*
X527153Y178161D01*
X527020Y177360D01*
Y176561D01*
X527153Y175761D01*
X527486Y174961D01*
X527886Y174427D01*
X528353Y174294D01*
X528820Y174561D01*
X529286Y175360D01*
G01X535153Y177894D02*
X537286D01*
X537086Y178827D01*
X536753Y179361D01*
X536286Y179627D01*
X535820Y179494D01*
X535420Y179094D01*
X535153Y178161D01*
X535020Y177360D01*
Y176561D01*
X535153Y175761D01*
X535486Y174961D01*
X535886Y174427D01*
X536353Y174294D01*
X536820Y174561D01*
X537286Y175360D01*
G01X540153Y174294D02*
Y182294D01*
G01X544153Y174294D02*
Y182294D01*
G01X548153Y179627D02*
Y174294D01*
G01Y181761D02*
X548020Y181894D01*
Y182161D01*
X548153Y182294D01*
X548286Y182161D01*
Y181894D01*
X548153Y181761D01*
G01X550953Y171627D02*
Y179627D01*
G01Y178427D02*
X551286Y179094D01*
X551620Y179494D01*
X552153Y179627D01*
X552620Y179494D01*
X553086Y178827D01*
X553286Y177894D01*
X553353Y176961D01*
X553286Y176027D01*
X553086Y175094D01*
X552686Y174561D01*
X552153Y174294D01*
X551686Y174427D01*
X551220Y174827D01*
X550953Y175360D01*
G01X555153Y175227D02*
X555486Y174694D01*
X555953Y174294D01*
X556353D01*
X556753Y174561D01*
X557020Y174961D01*
X557153Y175494D01*
X557086Y176294D01*
X556820Y176694D01*
X555620Y177494D01*
X555353Y178427D01*
X555486Y179094D01*
X555753Y179494D01*
X556153Y179627D01*
X556553Y179494D01*
X556953Y179094D01*
G01X559153Y177894D02*
X561286D01*
X561086Y178827D01*
X560753Y179361D01*
X560286Y179627D01*
X559820Y179494D01*
X559420Y179094D01*
X559153Y178161D01*
X559020Y177360D01*
Y176561D01*
X559153Y175761D01*
X559486Y174961D01*
X559886Y174427D01*
X560353Y174294D01*
X560820Y174561D01*
X561286Y175360D01*
G01X569353Y174294D02*
Y179627D01*
G01Y178694D02*
X569086Y179227D01*
X568686Y179494D01*
X568220Y179627D01*
X567753Y179361D01*
X567353Y178827D01*
X567086Y178027D01*
X566953Y176961D01*
X567086Y175894D01*
X567353Y175094D01*
X567753Y174561D01*
X568220Y174294D01*
X568686Y174427D01*
X569086Y174827D01*
X569353Y175360D01*
G01X571020Y174294D02*
Y179627D01*
G01Y178294D02*
X571286Y178961D01*
X571686Y179494D01*
X572220Y179627D01*
X572686Y179494D01*
X573086Y178961D01*
X573286Y178027D01*
Y174294D01*
G01X577353Y182294D02*
Y174294D01*
G01Y175494D02*
X577086Y174827D01*
X576686Y174427D01*
X576220Y174294D01*
X575686Y174561D01*
X575286Y175227D01*
X575020Y176027D01*
X574953Y176961D01*
X575020Y177894D01*
X575286Y178694D01*
X575686Y179361D01*
X576220Y179627D01*
X576686Y179494D01*
X577020Y179227D01*
X577353Y178694D01*
G01X584153Y174294D02*
X583753Y174427D01*
X583353Y174961D01*
X583086Y175894D01*
X582953Y176961D01*
X583086Y178027D01*
X583353Y178961D01*
X583753Y179494D01*
X584153Y179627D01*
X584553Y179494D01*
X584953Y178961D01*
X585220Y178027D01*
X585286Y176961D01*
X585220Y175894D01*
X584953Y174961D01*
X584553Y174427D01*
X584153Y174294D01*
G01X588153Y182294D02*
Y174294D01*
G01X587220Y179627D02*
X589086D01*
G01X591020Y174294D02*
Y182294D01*
G01Y178427D02*
X591353Y179094D01*
X591686Y179494D01*
X592220Y179627D01*
X592620Y179494D01*
X593086Y178961D01*
X593286Y178161D01*
Y174294D01*
G01X595153Y177894D02*
X597286D01*
X597086Y178827D01*
X596753Y179361D01*
X596286Y179627D01*
X595820Y179494D01*
X595420Y179094D01*
X595153Y178161D01*
X595020Y177360D01*
Y176561D01*
X595153Y175761D01*
X595486Y174961D01*
X595886Y174427D01*
X596353Y174294D01*
X596820Y174561D01*
X597286Y175360D01*
G01X599220Y174294D02*
Y179627D01*
G01Y178561D02*
X599553Y179094D01*
X599886Y179494D01*
X600353Y179627D01*
X600686Y179494D01*
X601086Y179094D01*
G01X603153Y175227D02*
X603486Y174694D01*
X603953Y174294D01*
X604353D01*
X604753Y174561D01*
X605020Y174961D01*
X605153Y175494D01*
X605086Y176294D01*
X604820Y176694D01*
X603620Y177494D01*
X603353Y178427D01*
X603486Y179094D01*
X603753Y179494D01*
X604153Y179627D01*
X604553Y179494D01*
X604953Y179094D01*
G01X608486Y171627D02*
X609153Y172961D01*
X609486Y174294D01*
Y179627D01*
X609153Y180961D01*
X608486Y182294D01*
G01X482820Y185794D02*
Y193794D01*
X484420D01*
X484953Y193394D01*
X485353Y192461D01*
X485486Y191394D01*
X485353Y190327D01*
X485020Y189527D01*
X484420Y189127D01*
X482820D01*
G01X488153Y193794D02*
Y185794D01*
G01X486620Y193794D02*
X489686D01*
G01X490753Y185794D02*
Y193794D01*
G01X493553D02*
Y185794D01*
G01Y189794D02*
X490753D01*
G01X494953Y185527D02*
X497353Y193794D01*
G01X498620Y185794D02*
Y193794D01*
X501686Y185794D01*
Y193794D01*
G01X502820Y185794D02*
Y193794D01*
X504420D01*
X504953Y193394D01*
X505353Y192461D01*
X505486Y191394D01*
X505353Y190327D01*
X505020Y189527D01*
X504420Y189127D01*
X502820D01*
G01X508153Y193794D02*
Y185794D01*
G01X506620Y193794D02*
X509686D01*
G01X510753Y185794D02*
Y193794D01*
G01X513553D02*
Y185794D01*
G01Y189794D02*
X510753D01*
G01X518820Y185794D02*
X521486Y188461D01*
X518820Y191127D01*
G01X523286Y187261D02*
X525020D01*
G01Y189661D02*
X523286D01*
G01X526686Y186994D02*
X527086Y186327D01*
X527553Y185927D01*
X528153Y185794D01*
X528753Y186061D01*
X529220Y186594D01*
X529553Y187527D01*
X529620Y188594D01*
X529486Y189661D01*
X529153Y190327D01*
X528686Y190861D01*
X528220Y190994D01*
X527753Y190861D01*
X527153Y190327D01*
X527353Y193794D01*
X529153D01*
G01X534153Y185794D02*
Y191127D01*
G01Y189661D02*
X534353Y190327D01*
X534686Y190861D01*
X535153Y191127D01*
X535620Y190861D01*
X535953Y190327D01*
X536153Y189661D01*
Y185794D01*
G01Y189661D02*
X536353Y190327D01*
X536686Y190861D01*
X537153Y191127D01*
X537620Y190861D01*
X537953Y190327D01*
X538153Y189527D01*
Y185794D01*
G01D02*
Y191127D01*
G01Y189661D02*
X538353Y190327D01*
X538686Y190861D01*
X539153Y191127D01*
X539620Y190861D01*
X539953Y190327D01*
X540153Y189661D01*
Y185794D01*
G01Y189661D02*
X540353Y190327D01*
X540686Y190861D01*
X541153Y191127D01*
X541620Y190861D01*
X541953Y190327D01*
X542153Y189527D01*
Y185794D01*
G01X483120Y198794D02*
Y206794D01*
X486186Y198794D01*
Y206794D01*
G01X487320Y198794D02*
Y206794D01*
X488920D01*
X489453Y206394D01*
X489853Y205461D01*
X489986Y204394D01*
X489853Y203327D01*
X489520Y202527D01*
X488920Y202127D01*
X487320D01*
G01X492653Y206794D02*
Y198794D01*
G01X491120Y206794D02*
X494186D01*
G01X495253Y198794D02*
Y206794D01*
G01X498053D02*
Y198794D01*
G01Y202794D02*
X495253D01*
G01X503253Y199860D02*
X503786Y199194D01*
X504386Y198794D01*
X504920D01*
X505453Y199194D01*
X505853Y199860D01*
X506053Y200794D01*
X505920Y201727D01*
X505586Y202527D01*
X504986Y203061D01*
X504186Y203327D01*
X503720Y203861D01*
X503520Y204794D01*
X503653Y205727D01*
X503986Y206394D01*
X504453Y206794D01*
X504920D01*
X505386Y206527D01*
X505786Y205861D01*
G01X508653Y204127D02*
Y198794D01*
G01Y206261D02*
X508520Y206394D01*
Y206661D01*
X508653Y206794D01*
X508786Y206661D01*
Y206394D01*
X508653Y206261D01*
G01X511653Y204127D02*
X513653D01*
X511653Y198794D01*
X513653D01*
G01X515653Y202394D02*
X517786D01*
X517586Y203327D01*
X517253Y203861D01*
X516786Y204127D01*
X516320Y203994D01*
X515920Y203594D01*
X515653Y202661D01*
X515520Y201860D01*
Y201061D01*
X515653Y200261D01*
X515986Y199461D01*
X516386Y198927D01*
X516853Y198794D01*
X517320Y199061D01*
X517786Y199860D01*
G01X523386Y205461D02*
X523786Y206261D01*
X524253Y206661D01*
X524786Y206794D01*
X525453Y206527D01*
X525920Y205861D01*
X526053Y205061D01*
X525986Y204260D01*
X525720Y203594D01*
X524386Y202261D01*
X523786Y201327D01*
X523386Y199994D01*
X523253Y198794D01*
X526053D01*
G01X528653Y198527D02*
X528520Y198661D01*
Y198927D01*
X528653Y199061D01*
X528786Y198927D01*
Y198661D01*
X528653Y198527D01*
G01X532653Y198794D02*
Y206794D01*
X531853Y205194D01*
G01Y198794D02*
X533453D01*
G01X536653D02*
X537120Y198927D01*
X537653Y199327D01*
X537986Y199994D01*
X538120Y200927D01*
X537986Y201860D01*
X537586Y202661D01*
X536986Y203061D01*
X536320D01*
X535920Y203327D01*
X535586Y203994D01*
X535453Y204927D01*
X535653Y205861D01*
X536120Y206527D01*
X536653Y206794D01*
X537186Y206527D01*
X537653Y205861D01*
X537853Y204927D01*
X537720Y203994D01*
X537386Y203327D01*
X536986Y203061D01*
X536320D01*
X535720Y202661D01*
X535320Y201860D01*
X535186Y200927D01*
X535320Y199994D01*
X535653Y199327D01*
X536186Y198927D01*
X536653Y198794D01*
G01X538653D02*
Y204127D01*
G01Y202661D02*
X538853Y203327D01*
X539186Y203861D01*
X539653Y204127D01*
X540120Y203861D01*
X540453Y203327D01*
X540653Y202661D01*
Y198794D01*
G01Y202661D02*
X540853Y203327D01*
X541186Y203861D01*
X541653Y204127D01*
X542120Y203861D01*
X542453Y203327D01*
X542653Y202527D01*
Y198794D01*
G01D02*
Y204127D01*
G01Y202661D02*
X542853Y203327D01*
X543186Y203861D01*
X543653Y204127D01*
X544120Y203861D01*
X544453Y203327D01*
X544653Y202661D01*
Y198794D01*
G01Y202661D02*
X544853Y203327D01*
X545186Y203861D01*
X545653Y204127D01*
X546120Y203861D01*
X546453Y203327D01*
X546653Y202527D01*
Y198794D01*
G01X552320Y196127D02*
X551653Y197461D01*
X551320Y198794D01*
Y204127D01*
X551653Y205461D01*
X552320Y206794D01*
G01X556653Y198794D02*
X556253Y198927D01*
X555853Y199461D01*
X555586Y200394D01*
X555453Y201461D01*
X555586Y202527D01*
X555853Y203461D01*
X556253Y203994D01*
X556653Y204127D01*
X557053Y203994D01*
X557453Y203461D01*
X557720Y202527D01*
X557786Y201461D01*
X557720Y200394D01*
X557453Y199461D01*
X557053Y198927D01*
X556653Y198794D01*
G01X559520D02*
Y204127D01*
G01Y202794D02*
X559786Y203461D01*
X560186Y203994D01*
X560720Y204127D01*
X561186Y203994D01*
X561586Y203461D01*
X561786Y202527D01*
Y198794D01*
G01X567453D02*
Y206794D01*
G01Y202794D02*
X567786Y203594D01*
X568186Y203994D01*
X568586Y204127D01*
X569186Y203861D01*
X569586Y203327D01*
X569853Y202394D01*
Y201327D01*
X569720Y200261D01*
X569453Y199461D01*
X568986Y198927D01*
X568586Y198794D01*
X568186Y198927D01*
X567786Y199327D01*
X567453Y199994D01*
G01X571720Y198794D02*
Y204127D01*
G01Y203061D02*
X572053Y203594D01*
X572386Y203994D01*
X572853Y204127D01*
X573186Y203994D01*
X573586Y203594D01*
G01X575653Y202394D02*
X577786D01*
X577586Y203327D01*
X577253Y203861D01*
X576786Y204127D01*
X576320Y203994D01*
X575920Y203594D01*
X575653Y202661D01*
X575520Y201860D01*
Y201061D01*
X575653Y200261D01*
X575986Y199461D01*
X576386Y198927D01*
X576853Y198794D01*
X577320Y199061D01*
X577786Y199860D01*
G01X581853Y198794D02*
Y204127D01*
G01Y203194D02*
X581586Y203727D01*
X581186Y203994D01*
X580720Y204127D01*
X580253Y203861D01*
X579853Y203327D01*
X579586Y202527D01*
X579453Y201461D01*
X579586Y200394D01*
X579853Y199594D01*
X580253Y199061D01*
X580720Y198794D01*
X581186Y198927D01*
X581586Y199327D01*
X581853Y199860D01*
G01X583520Y198794D02*
Y206794D01*
G01X585653Y204127D02*
X583520Y201061D01*
G01X584386Y202261D02*
X585786Y198794D01*
G01X589853D02*
Y204127D01*
G01Y203194D02*
X589586Y203727D01*
X589186Y203994D01*
X588720Y204127D01*
X588253Y203861D01*
X587853Y203327D01*
X587586Y202527D01*
X587453Y201461D01*
X587586Y200394D01*
X587853Y199594D01*
X588253Y199061D01*
X588720Y198794D01*
X589186Y198927D01*
X589586Y199327D01*
X589853Y199860D01*
G01X590986Y204127D02*
X591786Y198794D01*
X592653Y204127D01*
X593520Y198794D01*
X594320Y204127D01*
G01X597853Y198794D02*
Y204127D01*
G01Y203194D02*
X597586Y203727D01*
X597186Y203994D01*
X596720Y204127D01*
X596253Y203861D01*
X595853Y203327D01*
X595586Y202527D01*
X595453Y201461D01*
X595586Y200394D01*
X595853Y199594D01*
X596253Y199061D01*
X596720Y198794D01*
X597186Y198927D01*
X597586Y199327D01*
X597853Y199860D01*
G01X599253Y196394D02*
X599653Y196127D01*
X600186Y196394D01*
X600520Y196927D01*
X600786Y197594D01*
X601186Y199727D01*
X602053Y204127D01*
G01X599920D02*
X601186Y199727D01*
G01X604986Y196127D02*
X605653Y197461D01*
X605986Y198794D01*
Y204127D01*
X605653Y205461D01*
X604986Y206794D01*
G01X483120Y210794D02*
Y218794D01*
X486186Y210794D01*
Y218794D01*
G01X487320Y210794D02*
Y218794D01*
X488920D01*
X489453Y218394D01*
X489853Y217461D01*
X489986Y216394D01*
X489853Y215327D01*
X489520Y214527D01*
X488920Y214127D01*
X487320D01*
G01X492653Y218794D02*
Y210794D01*
G01X491120Y218794D02*
X494186D01*
G01X495253Y210794D02*
Y218794D01*
G01X498053D02*
Y210794D01*
G01Y214794D02*
X495253D01*
G01X503253Y211860D02*
X503786Y211194D01*
X504386Y210794D01*
X504920D01*
X505453Y211194D01*
X505853Y211860D01*
X506053Y212794D01*
X505920Y213727D01*
X505586Y214527D01*
X504986Y215061D01*
X504186Y215327D01*
X503720Y215861D01*
X503520Y216794D01*
X503653Y217727D01*
X503986Y218394D01*
X504453Y218794D01*
X504920D01*
X505386Y218527D01*
X505786Y217861D01*
G01X508653Y216127D02*
Y210794D01*
G01Y218261D02*
X508520Y218394D01*
Y218661D01*
X508653Y218794D01*
X508786Y218661D01*
Y218394D01*
X508653Y218261D01*
G01X511653Y216127D02*
X513653D01*
X511653Y210794D01*
X513653D01*
G01X515653Y214394D02*
X517786D01*
X517586Y215327D01*
X517253Y215861D01*
X516786Y216127D01*
X516320Y215994D01*
X515920Y215594D01*
X515653Y214661D01*
X515520Y213860D01*
Y213061D01*
X515653Y212261D01*
X515986Y211461D01*
X516386Y210927D01*
X516853Y210794D01*
X517320Y211061D01*
X517786Y211860D01*
G01X523186Y212394D02*
X523586Y211461D01*
X524120Y210927D01*
X524720Y210794D01*
X525253Y210927D01*
X525786Y211594D01*
X526120Y212394D01*
X526186Y213194D01*
X526053Y214127D01*
X525586Y214794D01*
X525120Y215061D01*
X524520D01*
G01X525120D02*
X525520Y215461D01*
X525853Y216127D01*
X525986Y216927D01*
X525853Y217727D01*
X525520Y218394D01*
X524920Y218794D01*
X524320Y218661D01*
X523720Y218127D01*
G01X528653Y210527D02*
X528520Y210661D01*
Y210927D01*
X528653Y211061D01*
X528786Y210927D01*
Y210661D01*
X528653Y210527D01*
G01X531186Y211994D02*
X531586Y211327D01*
X532053Y210927D01*
X532653Y210794D01*
X533253Y211061D01*
X533720Y211594D01*
X534053Y212527D01*
X534120Y213594D01*
X533986Y214661D01*
X533653Y215327D01*
X533186Y215861D01*
X532720Y215994D01*
X532253Y215861D01*
X531653Y215327D01*
X531853Y218794D01*
X533653D01*
G01X535186Y211994D02*
X535586Y211327D01*
X536053Y210927D01*
X536653Y210794D01*
X537253Y211061D01*
X537720Y211594D01*
X538053Y212527D01*
X538120Y213594D01*
X537986Y214661D01*
X537653Y215327D01*
X537186Y215861D01*
X536720Y215994D01*
X536253Y215861D01*
X535653Y215327D01*
X535853Y218794D01*
X537653D01*
G01X538653Y210794D02*
Y216127D01*
G01Y214661D02*
X538853Y215327D01*
X539186Y215861D01*
X539653Y216127D01*
X540120Y215861D01*
X540453Y215327D01*
X540653Y214661D01*
Y210794D01*
G01Y214661D02*
X540853Y215327D01*
X541186Y215861D01*
X541653Y216127D01*
X542120Y215861D01*
X542453Y215327D01*
X542653Y214527D01*
Y210794D01*
G01D02*
Y216127D01*
G01Y214661D02*
X542853Y215327D01*
X543186Y215861D01*
X543653Y216127D01*
X544120Y215861D01*
X544453Y215327D01*
X544653Y214661D01*
Y210794D01*
G01Y214661D02*
X544853Y215327D01*
X545186Y215861D01*
X545653Y216127D01*
X546120Y215861D01*
X546453Y215327D01*
X546653Y214527D01*
Y210794D01*
G01X552320Y208127D02*
X551653Y209461D01*
X551320Y210794D01*
Y216127D01*
X551653Y217461D01*
X552320Y218794D01*
G01X556653Y210794D02*
X556253Y210927D01*
X555853Y211461D01*
X555586Y212394D01*
X555453Y213461D01*
X555586Y214527D01*
X555853Y215461D01*
X556253Y215994D01*
X556653Y216127D01*
X557053Y215994D01*
X557453Y215461D01*
X557720Y214527D01*
X557786Y213461D01*
X557720Y212394D01*
X557453Y211461D01*
X557053Y210927D01*
X556653Y210794D01*
G01X559520D02*
Y216127D01*
G01Y214794D02*
X559786Y215461D01*
X560186Y215994D01*
X560720Y216127D01*
X561186Y215994D01*
X561586Y215461D01*
X561786Y214527D01*
Y210794D01*
G01X567453D02*
Y218794D01*
G01Y214794D02*
X567786Y215594D01*
X568186Y215994D01*
X568586Y216127D01*
X569186Y215861D01*
X569586Y215327D01*
X569853Y214394D01*
Y213327D01*
X569720Y212261D01*
X569453Y211461D01*
X568986Y210927D01*
X568586Y210794D01*
X568186Y210927D01*
X567786Y211327D01*
X567453Y211994D01*
G01X571720Y210794D02*
Y216127D01*
G01Y215061D02*
X572053Y215594D01*
X572386Y215994D01*
X572853Y216127D01*
X573186Y215994D01*
X573586Y215594D01*
G01X575653Y214394D02*
X577786D01*
X577586Y215327D01*
X577253Y215861D01*
X576786Y216127D01*
X576320Y215994D01*
X575920Y215594D01*
X575653Y214661D01*
X575520Y213860D01*
Y213061D01*
X575653Y212261D01*
X575986Y211461D01*
X576386Y210927D01*
X576853Y210794D01*
X577320Y211061D01*
X577786Y211860D01*
G01X581853Y210794D02*
Y216127D01*
G01Y215194D02*
X581586Y215727D01*
X581186Y215994D01*
X580720Y216127D01*
X580253Y215861D01*
X579853Y215327D01*
X579586Y214527D01*
X579453Y213461D01*
X579586Y212394D01*
X579853Y211594D01*
X580253Y211061D01*
X580720Y210794D01*
X581186Y210927D01*
X581586Y211327D01*
X581853Y211860D01*
G01X583520Y210794D02*
Y218794D01*
G01X585653Y216127D02*
X583520Y213061D01*
G01X584386Y214261D02*
X585786Y210794D01*
G01X589853D02*
Y216127D01*
G01Y215194D02*
X589586Y215727D01*
X589186Y215994D01*
X588720Y216127D01*
X588253Y215861D01*
X587853Y215327D01*
X587586Y214527D01*
X587453Y213461D01*
X587586Y212394D01*
X587853Y211594D01*
X588253Y211061D01*
X588720Y210794D01*
X589186Y210927D01*
X589586Y211327D01*
X589853Y211860D01*
G01X590986Y216127D02*
X591786Y210794D01*
X592653Y216127D01*
X593520Y210794D01*
X594320Y216127D01*
G01X597853Y210794D02*
Y216127D01*
G01Y215194D02*
X597586Y215727D01*
X597186Y215994D01*
X596720Y216127D01*
X596253Y215861D01*
X595853Y215327D01*
X595586Y214527D01*
X595453Y213461D01*
X595586Y212394D01*
X595853Y211594D01*
X596253Y211061D01*
X596720Y210794D01*
X597186Y210927D01*
X597586Y211327D01*
X597853Y211860D01*
G01X599253Y208394D02*
X599653Y208127D01*
X600186Y208394D01*
X600520Y208927D01*
X600786Y209594D01*
X601186Y211727D01*
X602053Y216127D01*
G01X599920D02*
X601186Y211727D01*
G01X604986Y208127D02*
X605653Y209461D01*
X605986Y210794D01*
Y216127D01*
X605653Y217461D01*
X604986Y218794D01*
G01X483120Y224294D02*
Y232294D01*
X486186Y224294D01*
Y232294D01*
G01X487320Y224294D02*
Y232294D01*
X488920D01*
X489453Y231894D01*
X489853Y230961D01*
X489986Y229894D01*
X489853Y228827D01*
X489520Y228027D01*
X488920Y227627D01*
X487320D01*
G01X492653Y232294D02*
Y224294D01*
G01X491120Y232294D02*
X494186D01*
G01X495253Y224294D02*
Y232294D01*
G01X498053D02*
Y224294D01*
G01Y228294D02*
X495253D01*
G01X503253Y225360D02*
X503786Y224694D01*
X504386Y224294D01*
X504920D01*
X505453Y224694D01*
X505853Y225360D01*
X506053Y226294D01*
X505920Y227227D01*
X505586Y228027D01*
X504986Y228561D01*
X504186Y228827D01*
X503720Y229361D01*
X503520Y230294D01*
X503653Y231227D01*
X503986Y231894D01*
X504453Y232294D01*
X504920D01*
X505386Y232027D01*
X505786Y231361D01*
G01X508653Y229627D02*
Y224294D01*
G01Y231761D02*
X508520Y231894D01*
Y232161D01*
X508653Y232294D01*
X508786Y232161D01*
Y231894D01*
X508653Y231761D01*
G01X511653Y229627D02*
X513653D01*
X511653Y224294D01*
X513653D01*
G01X515653Y227894D02*
X517786D01*
X517586Y228827D01*
X517253Y229361D01*
X516786Y229627D01*
X516320Y229494D01*
X515920Y229094D01*
X515653Y228161D01*
X515520Y227360D01*
Y226561D01*
X515653Y225761D01*
X515986Y224961D01*
X516386Y224427D01*
X516853Y224294D01*
X517320Y224561D01*
X517786Y225360D01*
G01X521986Y224294D02*
X519320Y226961D01*
X521986Y229627D01*
G01X527186Y225494D02*
X527586Y224827D01*
X528053Y224427D01*
X528653Y224294D01*
X529253Y224561D01*
X529720Y225094D01*
X530053Y226027D01*
X530120Y227094D01*
X529986Y228161D01*
X529653Y228827D01*
X529186Y229361D01*
X528720Y229494D01*
X528253Y229361D01*
X527653Y228827D01*
X527853Y232294D01*
X529653D01*
G01X530653Y224294D02*
Y229627D01*
G01Y228161D02*
X530853Y228827D01*
X531186Y229361D01*
X531653Y229627D01*
X532120Y229361D01*
X532453Y228827D01*
X532653Y228161D01*
Y224294D01*
G01Y228161D02*
X532853Y228827D01*
X533186Y229361D01*
X533653Y229627D01*
X534120Y229361D01*
X534453Y228827D01*
X534653Y228027D01*
Y224294D01*
G01D02*
Y229627D01*
G01Y228161D02*
X534853Y228827D01*
X535186Y229361D01*
X535653Y229627D01*
X536120Y229361D01*
X536453Y228827D01*
X536653Y228161D01*
Y224294D01*
G01Y228161D02*
X536853Y228827D01*
X537186Y229361D01*
X537653Y229627D01*
X538120Y229361D01*
X538453Y228827D01*
X538653Y228027D01*
Y224294D01*
G01X544320Y221627D02*
X543653Y222961D01*
X543320Y224294D01*
Y229627D01*
X543653Y230961D01*
X544320Y232294D01*
G01X547520Y224294D02*
Y229627D01*
G01Y228294D02*
X547786Y228961D01*
X548186Y229494D01*
X548720Y229627D01*
X549186Y229494D01*
X549586Y228961D01*
X549786Y228027D01*
Y224294D01*
G01X552653D02*
X552253Y224427D01*
X551853Y224961D01*
X551586Y225894D01*
X551453Y226961D01*
X551586Y228027D01*
X551853Y228961D01*
X552253Y229494D01*
X552653Y229627D01*
X553053Y229494D01*
X553453Y228961D01*
X553720Y228027D01*
X553786Y226961D01*
X553720Y225894D01*
X553453Y224961D01*
X553053Y224427D01*
X552653Y224294D01*
G01X556653Y232294D02*
Y224294D01*
G01X555720Y229627D02*
X557586D01*
G01X564653Y224294D02*
X564253Y224427D01*
X563853Y224961D01*
X563586Y225894D01*
X563453Y226961D01*
X563586Y228027D01*
X563853Y228961D01*
X564253Y229494D01*
X564653Y229627D01*
X565053Y229494D01*
X565453Y228961D01*
X565720Y228027D01*
X565786Y226961D01*
X565720Y225894D01*
X565453Y224961D01*
X565053Y224427D01*
X564653Y224294D01*
G01X567520D02*
Y229627D01*
G01Y228294D02*
X567786Y228961D01*
X568186Y229494D01*
X568720Y229627D01*
X569186Y229494D01*
X569586Y228961D01*
X569786Y228027D01*
Y224294D01*
G01X575453D02*
Y232294D01*
G01Y228294D02*
X575786Y229094D01*
X576186Y229494D01*
X576586Y229627D01*
X577186Y229361D01*
X577586Y228827D01*
X577853Y227894D01*
Y226827D01*
X577720Y225761D01*
X577453Y224961D01*
X576986Y224427D01*
X576586Y224294D01*
X576186Y224427D01*
X575786Y224827D01*
X575453Y225494D01*
G01X579720Y224294D02*
Y229627D01*
G01Y228561D02*
X580053Y229094D01*
X580386Y229494D01*
X580853Y229627D01*
X581186Y229494D01*
X581586Y229094D01*
G01X583653Y227894D02*
X585786D01*
X585586Y228827D01*
X585253Y229361D01*
X584786Y229627D01*
X584320Y229494D01*
X583920Y229094D01*
X583653Y228161D01*
X583520Y227360D01*
Y226561D01*
X583653Y225761D01*
X583986Y224961D01*
X584386Y224427D01*
X584853Y224294D01*
X585320Y224561D01*
X585786Y225360D01*
G01X589853Y224294D02*
Y229627D01*
G01Y228694D02*
X589586Y229227D01*
X589186Y229494D01*
X588720Y229627D01*
X588253Y229361D01*
X587853Y228827D01*
X587586Y228027D01*
X587453Y226961D01*
X587586Y225894D01*
X587853Y225094D01*
X588253Y224561D01*
X588720Y224294D01*
X589186Y224427D01*
X589586Y224827D01*
X589853Y225360D01*
G01X591520Y224294D02*
Y232294D01*
G01X593653Y229627D02*
X591520Y226561D01*
G01X592386Y227761D02*
X593786Y224294D01*
G01X597853D02*
Y229627D01*
G01Y228694D02*
X597586Y229227D01*
X597186Y229494D01*
X596720Y229627D01*
X596253Y229361D01*
X595853Y228827D01*
X595586Y228027D01*
X595453Y226961D01*
X595586Y225894D01*
X595853Y225094D01*
X596253Y224561D01*
X596720Y224294D01*
X597186Y224427D01*
X597586Y224827D01*
X597853Y225360D01*
G01X598986Y229627D02*
X599786Y224294D01*
X600653Y229627D01*
X601520Y224294D01*
X602320Y229627D01*
G01X605853Y224294D02*
Y229627D01*
G01Y228694D02*
X605586Y229227D01*
X605186Y229494D01*
X604720Y229627D01*
X604253Y229361D01*
X603853Y228827D01*
X603586Y228027D01*
X603453Y226961D01*
X603586Y225894D01*
X603853Y225094D01*
X604253Y224561D01*
X604720Y224294D01*
X605186Y224427D01*
X605586Y224827D01*
X605853Y225360D01*
G01X607253Y221894D02*
X607653Y221627D01*
X608186Y221894D01*
X608520Y222427D01*
X608786Y223094D01*
X609186Y225227D01*
X610053Y229627D01*
G01X607920D02*
X609186Y225227D01*
G01X612986Y221627D02*
X613653Y222961D01*
X613986Y224294D01*
Y229627D01*
X613653Y230961D01*
X612986Y232294D01*
G01X483320Y235627D02*
X482653Y236961D01*
X482320Y238294D01*
Y243627D01*
X482653Y244961D01*
X483320Y246294D01*
G01X486253Y239360D02*
X486786Y238694D01*
X487386Y238294D01*
X487920D01*
X488453Y238694D01*
X488853Y239360D01*
X489053Y240294D01*
X488920Y241227D01*
X488586Y242027D01*
X487986Y242561D01*
X487186Y242827D01*
X486720Y243361D01*
X486520Y244294D01*
X486653Y245227D01*
X486986Y245894D01*
X487453Y246294D01*
X487920D01*
X488386Y246027D01*
X488786Y245361D01*
G01X490520Y243627D02*
Y239894D01*
X490786Y238961D01*
X491186Y238427D01*
X491653Y238294D01*
X492120Y238427D01*
X492520Y238961D01*
X492786Y239894D01*
G01Y238294D02*
Y243627D01*
G01X494720Y238294D02*
Y243627D01*
G01Y242561D02*
X495053Y243094D01*
X495386Y243494D01*
X495853Y243627D01*
X496186Y243494D01*
X496586Y243094D01*
G01X499253Y238294D02*
Y245094D01*
X499386Y245761D01*
X499653Y246161D01*
X500053Y246294D01*
X500453Y246027D01*
X500653Y245361D01*
G01X499853Y243094D02*
X498520D01*
G01X504853Y238294D02*
Y243627D01*
G01Y242694D02*
X504586Y243227D01*
X504186Y243494D01*
X503720Y243627D01*
X503253Y243361D01*
X502853Y242827D01*
X502586Y242027D01*
X502453Y240961D01*
X502586Y239894D01*
X502853Y239094D01*
X503253Y238561D01*
X503720Y238294D01*
X504186Y238427D01*
X504586Y238827D01*
X504853Y239360D01*
G01X508720Y242961D02*
X508253Y243494D01*
X507853Y243627D01*
X507320Y243361D01*
X506920Y242827D01*
X506653Y241894D01*
X506586Y240961D01*
X506653Y240027D01*
X506920Y239227D01*
X507320Y238561D01*
X507853Y238294D01*
X508320Y238561D01*
X508720Y239094D01*
G01X510653Y241894D02*
X512786D01*
X512586Y242827D01*
X512253Y243361D01*
X511786Y243627D01*
X511320Y243494D01*
X510920Y243094D01*
X510653Y242161D01*
X510520Y241360D01*
Y240561D01*
X510653Y239761D01*
X510986Y238961D01*
X511386Y238427D01*
X511853Y238294D01*
X512320Y238561D01*
X512786Y239360D01*
G01X519653Y246294D02*
Y238294D01*
G01X518720Y243627D02*
X520586D01*
G01X522720Y238294D02*
Y243627D01*
G01Y242561D02*
X523053Y243094D01*
X523386Y243494D01*
X523853Y243627D01*
X524186Y243494D01*
X524586Y243094D01*
G01X526653Y241894D02*
X528786D01*
X528586Y242827D01*
X528253Y243361D01*
X527786Y243627D01*
X527320Y243494D01*
X526920Y243094D01*
X526653Y242161D01*
X526520Y241360D01*
Y240561D01*
X526653Y239761D01*
X526986Y238961D01*
X527386Y238427D01*
X527853Y238294D01*
X528320Y238561D01*
X528786Y239360D01*
G01X532853Y238294D02*
Y243627D01*
G01Y242694D02*
X532586Y243227D01*
X532186Y243494D01*
X531720Y243627D01*
X531253Y243361D01*
X530853Y242827D01*
X530586Y242027D01*
X530453Y240961D01*
X530586Y239894D01*
X530853Y239094D01*
X531253Y238561D01*
X531720Y238294D01*
X532186Y238427D01*
X532586Y238827D01*
X532853Y239360D01*
G01X535653Y246294D02*
Y238294D01*
G01X534720Y243627D02*
X536586D01*
G01X537653Y238294D02*
Y243627D01*
G01Y242161D02*
X537853Y242827D01*
X538186Y243361D01*
X538653Y243627D01*
X539120Y243361D01*
X539453Y242827D01*
X539653Y242161D01*
Y238294D01*
G01Y242161D02*
X539853Y242827D01*
X540186Y243361D01*
X540653Y243627D01*
X541120Y243361D01*
X541453Y242827D01*
X541653Y242027D01*
Y238294D01*
G01X542653Y241894D02*
X544786D01*
X544586Y242827D01*
X544253Y243361D01*
X543786Y243627D01*
X543320Y243494D01*
X542920Y243094D01*
X542653Y242161D01*
X542520Y241360D01*
Y240561D01*
X542653Y239761D01*
X542986Y238961D01*
X543386Y238427D01*
X543853Y238294D01*
X544320Y238561D01*
X544786Y239360D01*
G01X546520Y238294D02*
Y243627D01*
G01Y242294D02*
X546786Y242961D01*
X547186Y243494D01*
X547720Y243627D01*
X548186Y243494D01*
X548586Y242961D01*
X548786Y242027D01*
Y238294D01*
G01X551653Y246294D02*
Y238294D01*
G01X550720Y243627D02*
X552586D01*
G01X559653D02*
Y238294D01*
G01Y245761D02*
X559520Y245894D01*
Y246161D01*
X559653Y246294D01*
X559786Y246161D01*
Y245894D01*
X559653Y245761D01*
G01X562653Y239227D02*
X562986Y238694D01*
X563453Y238294D01*
X563853D01*
X564253Y238561D01*
X564520Y238961D01*
X564653Y239494D01*
X564586Y240294D01*
X564320Y240694D01*
X563120Y241494D01*
X562853Y242427D01*
X562986Y243094D01*
X563253Y243494D01*
X563653Y243627D01*
X564053Y243494D01*
X564453Y243094D01*
G01X570253Y238294D02*
Y246294D01*
G01X573053D02*
Y238294D01*
G01Y242294D02*
X570253D01*
G01X573986Y238294D02*
X575653Y246294D01*
X577320Y238294D01*
G01X576720Y241094D02*
X574586D01*
G01X578253Y239360D02*
X578786Y238694D01*
X579386Y238294D01*
X579920D01*
X580453Y238694D01*
X580853Y239360D01*
X581053Y240294D01*
X580920Y241227D01*
X580586Y242027D01*
X579986Y242561D01*
X579186Y242827D01*
X578720Y243361D01*
X578520Y244294D01*
X578653Y245227D01*
X578986Y245894D01*
X579453Y246294D01*
X579920D01*
X580386Y246027D01*
X580786Y245361D01*
G01X582320Y246294D02*
Y238294D01*
X584986D01*
G01X591653D02*
X591253Y238427D01*
X590853Y238961D01*
X590586Y239894D01*
X590453Y240961D01*
X590586Y242027D01*
X590853Y242961D01*
X591253Y243494D01*
X591653Y243627D01*
X592053Y243494D01*
X592453Y242961D01*
X592720Y242027D01*
X592786Y240961D01*
X592720Y239894D01*
X592453Y238961D01*
X592053Y238427D01*
X591653Y238294D01*
G01X594720D02*
Y243627D01*
G01Y242561D02*
X595053Y243094D01*
X595386Y243494D01*
X595853Y243627D01*
X596186Y243494D01*
X596586Y243094D01*
G01X602320Y246294D02*
Y238294D01*
X604986D01*
G01X606653Y241894D02*
X608786D01*
X608586Y242827D01*
X608253Y243361D01*
X607786Y243627D01*
X607320Y243494D01*
X606920Y243094D01*
X606653Y242161D01*
X606520Y241360D01*
Y240561D01*
X606653Y239761D01*
X606986Y238961D01*
X607386Y238427D01*
X607853Y238294D01*
X608320Y238561D01*
X608786Y239360D01*
G01X612853Y238294D02*
Y243627D01*
G01Y242694D02*
X612586Y243227D01*
X612186Y243494D01*
X611720Y243627D01*
X611253Y243361D01*
X610853Y242827D01*
X610586Y242027D01*
X610453Y240961D01*
X610586Y239894D01*
X610853Y239094D01*
X611253Y238561D01*
X611720Y238294D01*
X612186Y238427D01*
X612586Y238827D01*
X612853Y239360D01*
G01X616853Y246294D02*
Y238294D01*
G01Y239494D02*
X616586Y238827D01*
X616186Y238427D01*
X615720Y238294D01*
X615186Y238561D01*
X614786Y239227D01*
X614520Y240027D01*
X614453Y240961D01*
X614520Y241894D01*
X614786Y242694D01*
X615186Y243361D01*
X615720Y243627D01*
X616186Y243494D01*
X616520Y243227D01*
X616853Y242694D01*
G01X622386Y238294D02*
Y246294D01*
X624920D01*
G01X623986Y242427D02*
X622386D01*
G01X626720Y238294D02*
Y243627D01*
G01Y242561D02*
X627053Y243094D01*
X627386Y243494D01*
X627853Y243627D01*
X628186Y243494D01*
X628586Y243094D01*
G01X630653Y241894D02*
X632786D01*
X632586Y242827D01*
X632253Y243361D01*
X631786Y243627D01*
X631320Y243494D01*
X630920Y243094D01*
X630653Y242161D01*
X630520Y241360D01*
Y240561D01*
X630653Y239761D01*
X630986Y238961D01*
X631386Y238427D01*
X631853Y238294D01*
X632320Y238561D01*
X632786Y239360D01*
G01X634653Y241894D02*
X636786D01*
X636586Y242827D01*
X636253Y243361D01*
X635786Y243627D01*
X635320Y243494D01*
X634920Y243094D01*
X634653Y242161D01*
X634520Y241360D01*
Y240561D01*
X634653Y239761D01*
X634986Y238961D01*
X635386Y238427D01*
X635853Y238294D01*
X636320Y238561D01*
X636786Y239360D01*
G01X642253Y238294D02*
Y246294D01*
G01X645053D02*
Y238294D01*
G01Y242294D02*
X642253D01*
G01X645986Y238294D02*
X647653Y246294D01*
X649320Y238294D01*
G01X648720Y241094D02*
X646586D01*
G01X650253Y239360D02*
X650786Y238694D01*
X651386Y238294D01*
X651920D01*
X652453Y238694D01*
X652853Y239360D01*
X653053Y240294D01*
X652920Y241227D01*
X652586Y242027D01*
X651986Y242561D01*
X651186Y242827D01*
X650720Y243361D01*
X650520Y244294D01*
X650653Y245227D01*
X650986Y245894D01*
X651453Y246294D01*
X651920D01*
X652386Y246027D01*
X652786Y245361D01*
G01X654320Y246294D02*
Y238294D01*
X656986D01*
G01X659986Y235627D02*
X660653Y236961D01*
X660986Y238294D01*
Y243627D01*
X660653Y244961D01*
X659986Y246294D01*
G01X482320Y258627D02*
X481653Y259961D01*
X481320Y261294D01*
Y266627D01*
X481653Y267961D01*
X482320Y269294D01*
G01X485253Y262360D02*
X485786Y261694D01*
X486386Y261294D01*
X486920D01*
X487453Y261694D01*
X487853Y262360D01*
X488053Y263294D01*
X487920Y264227D01*
X487586Y265027D01*
X486986Y265561D01*
X486186Y265827D01*
X485720Y266361D01*
X485520Y267294D01*
X485653Y268227D01*
X485986Y268894D01*
X486453Y269294D01*
X486920D01*
X487386Y269027D01*
X487786Y268361D01*
G01X489520Y266627D02*
Y262894D01*
X489786Y261961D01*
X490186Y261427D01*
X490653Y261294D01*
X491120Y261427D01*
X491520Y261961D01*
X491786Y262894D01*
G01Y261294D02*
Y266627D01*
G01X493720Y261294D02*
Y266627D01*
G01Y265561D02*
X494053Y266094D01*
X494386Y266494D01*
X494853Y266627D01*
X495186Y266494D01*
X495586Y266094D01*
G01X498253Y261294D02*
Y268094D01*
X498386Y268761D01*
X498653Y269161D01*
X499053Y269294D01*
X499453Y269027D01*
X499653Y268361D01*
G01X498853Y266094D02*
X497520D01*
G01X503853Y261294D02*
Y266627D01*
G01Y265694D02*
X503586Y266227D01*
X503186Y266494D01*
X502720Y266627D01*
X502253Y266361D01*
X501853Y265827D01*
X501586Y265027D01*
X501453Y263961D01*
X501586Y262894D01*
X501853Y262094D01*
X502253Y261561D01*
X502720Y261294D01*
X503186Y261427D01*
X503586Y261827D01*
X503853Y262360D01*
G01X507720Y265961D02*
X507253Y266494D01*
X506853Y266627D01*
X506320Y266361D01*
X505920Y265827D01*
X505653Y264894D01*
X505586Y263961D01*
X505653Y263027D01*
X505920Y262227D01*
X506320Y261561D01*
X506853Y261294D01*
X507320Y261561D01*
X507720Y262094D01*
G01X509653Y264894D02*
X511786D01*
X511586Y265827D01*
X511253Y266361D01*
X510786Y266627D01*
X510320Y266494D01*
X509920Y266094D01*
X509653Y265161D01*
X509520Y264360D01*
Y263561D01*
X509653Y262761D01*
X509986Y261961D01*
X510386Y261427D01*
X510853Y261294D01*
X511320Y261561D01*
X511786Y262360D01*
G01X518653Y269294D02*
Y261294D01*
G01X517720Y266627D02*
X519586D01*
G01X521720Y261294D02*
Y266627D01*
G01Y265561D02*
X522053Y266094D01*
X522386Y266494D01*
X522853Y266627D01*
X523186Y266494D01*
X523586Y266094D01*
G01X525653Y264894D02*
X527786D01*
X527586Y265827D01*
X527253Y266361D01*
X526786Y266627D01*
X526320Y266494D01*
X525920Y266094D01*
X525653Y265161D01*
X525520Y264360D01*
Y263561D01*
X525653Y262761D01*
X525986Y261961D01*
X526386Y261427D01*
X526853Y261294D01*
X527320Y261561D01*
X527786Y262360D01*
G01X531853Y261294D02*
Y266627D01*
G01Y265694D02*
X531586Y266227D01*
X531186Y266494D01*
X530720Y266627D01*
X530253Y266361D01*
X529853Y265827D01*
X529586Y265027D01*
X529453Y263961D01*
X529586Y262894D01*
X529853Y262094D01*
X530253Y261561D01*
X530720Y261294D01*
X531186Y261427D01*
X531586Y261827D01*
X531853Y262360D01*
G01X534653Y269294D02*
Y261294D01*
G01X533720Y266627D02*
X535586D01*
G01X536653Y261294D02*
Y266627D01*
G01Y265161D02*
X536853Y265827D01*
X537186Y266361D01*
X537653Y266627D01*
X538120Y266361D01*
X538453Y265827D01*
X538653Y265161D01*
Y261294D01*
G01Y265161D02*
X538853Y265827D01*
X539186Y266361D01*
X539653Y266627D01*
X540120Y266361D01*
X540453Y265827D01*
X540653Y265027D01*
Y261294D01*
G01X541653Y264894D02*
X543786D01*
X543586Y265827D01*
X543253Y266361D01*
X542786Y266627D01*
X542320Y266494D01*
X541920Y266094D01*
X541653Y265161D01*
X541520Y264360D01*
Y263561D01*
X541653Y262761D01*
X541986Y261961D01*
X542386Y261427D01*
X542853Y261294D01*
X543320Y261561D01*
X543786Y262360D01*
G01X545520Y261294D02*
Y266627D01*
G01Y265294D02*
X545786Y265961D01*
X546186Y266494D01*
X546720Y266627D01*
X547186Y266494D01*
X547586Y265961D01*
X547786Y265027D01*
Y261294D01*
G01X550653Y269294D02*
Y261294D01*
G01X549720Y266627D02*
X551586D01*
G01X558653D02*
Y261294D01*
G01Y268761D02*
X558520Y268894D01*
Y269161D01*
X558653Y269294D01*
X558786Y269161D01*
Y268894D01*
X558653Y268761D01*
G01X561653Y262227D02*
X561986Y261694D01*
X562453Y261294D01*
X562853D01*
X563253Y261561D01*
X563520Y261961D01*
X563653Y262494D01*
X563586Y263294D01*
X563320Y263694D01*
X562120Y264494D01*
X561853Y265427D01*
X561986Y266094D01*
X562253Y266494D01*
X562653Y266627D01*
X563053Y266494D01*
X563453Y266094D01*
G01X570653Y266627D02*
Y261294D01*
G01Y268761D02*
X570520Y268894D01*
Y269161D01*
X570653Y269294D01*
X570786Y269161D01*
Y268894D01*
X570653Y268761D01*
G01X572653Y261294D02*
Y266627D01*
G01Y265161D02*
X572853Y265827D01*
X573186Y266361D01*
X573653Y266627D01*
X574120Y266361D01*
X574453Y265827D01*
X574653Y265161D01*
Y261294D01*
G01Y265161D02*
X574853Y265827D01*
X575186Y266361D01*
X575653Y266627D01*
X576120Y266361D01*
X576453Y265827D01*
X576653Y265027D01*
Y261294D01*
G01D02*
Y266627D01*
G01Y265161D02*
X576853Y265827D01*
X577186Y266361D01*
X577653Y266627D01*
X578120Y266361D01*
X578453Y265827D01*
X578653Y265161D01*
Y261294D01*
G01Y265161D02*
X578853Y265827D01*
X579186Y266361D01*
X579653Y266627D01*
X580120Y266361D01*
X580453Y265827D01*
X580653Y265027D01*
Y261294D01*
G01X581653Y264894D02*
X583786D01*
X583586Y265827D01*
X583253Y266361D01*
X582786Y266627D01*
X582320Y266494D01*
X581920Y266094D01*
X581653Y265161D01*
X581520Y264360D01*
Y263561D01*
X581653Y262761D01*
X581986Y261961D01*
X582386Y261427D01*
X582853Y261294D01*
X583320Y261561D01*
X583786Y262360D01*
G01X585720Y261294D02*
Y266627D01*
G01Y265561D02*
X586053Y266094D01*
X586386Y266494D01*
X586853Y266627D01*
X587186Y266494D01*
X587586Y266094D01*
G01X589653Y262227D02*
X589986Y261694D01*
X590453Y261294D01*
X590853D01*
X591253Y261561D01*
X591520Y261961D01*
X591653Y262494D01*
X591586Y263294D01*
X591320Y263694D01*
X590120Y264494D01*
X589853Y265427D01*
X589986Y266094D01*
X590253Y266494D01*
X590653Y266627D01*
X591053Y266494D01*
X591453Y266094D01*
G01X594653Y266627D02*
Y261294D01*
G01Y268761D02*
X594520Y268894D01*
Y269161D01*
X594653Y269294D01*
X594786Y269161D01*
Y268894D01*
X594653Y268761D01*
G01X598653Y261294D02*
X598253Y261427D01*
X597853Y261961D01*
X597586Y262894D01*
X597453Y263961D01*
X597586Y265027D01*
X597853Y265961D01*
X598253Y266494D01*
X598653Y266627D01*
X599053Y266494D01*
X599453Y265961D01*
X599720Y265027D01*
X599786Y263961D01*
X599720Y262894D01*
X599453Y261961D01*
X599053Y261427D01*
X598653Y261294D01*
G01X601520D02*
Y266627D01*
G01Y265294D02*
X601786Y265961D01*
X602186Y266494D01*
X602720Y266627D01*
X603186Y266494D01*
X603586Y265961D01*
X603786Y265027D01*
Y261294D01*
G01X611053Y265294D02*
X612386D01*
Y262894D01*
X611986Y262094D01*
X611520Y261561D01*
X610853Y261294D01*
X610186Y261561D01*
X609720Y262094D01*
X609320Y262894D01*
X609053Y263827D01*
X608920Y264894D01*
Y265827D01*
X609053Y266627D01*
X609320Y267561D01*
X609720Y268361D01*
X610120Y268894D01*
X610653Y269294D01*
X611120D01*
X611653Y269027D01*
X612053Y268494D01*
G01X614653Y261294D02*
X614253Y261427D01*
X613853Y261961D01*
X613586Y262894D01*
X613453Y263961D01*
X613586Y265027D01*
X613853Y265961D01*
X614253Y266494D01*
X614653Y266627D01*
X615053Y266494D01*
X615453Y265961D01*
X615720Y265027D01*
X615786Y263961D01*
X615720Y262894D01*
X615453Y261961D01*
X615053Y261427D01*
X614653Y261294D01*
G01X618653D02*
Y269294D01*
G01X623853D02*
Y261294D01*
G01Y262494D02*
X623586Y261827D01*
X623186Y261427D01*
X622720Y261294D01*
X622186Y261561D01*
X621786Y262227D01*
X621520Y263027D01*
X621453Y263961D01*
X621520Y264894D01*
X621786Y265694D01*
X622186Y266361D01*
X622720Y266627D01*
X623186Y266494D01*
X623520Y266227D01*
X623853Y265694D01*
G01X626520Y259827D02*
X626786Y261561D01*
G01X631986Y261294D02*
X629320D01*
Y269294D01*
X631986D01*
G01X630920Y265427D02*
X629320D01*
G01X633520Y261294D02*
Y266627D01*
G01Y265294D02*
X633786Y265961D01*
X634186Y266494D01*
X634720Y266627D01*
X635186Y266494D01*
X635586Y265961D01*
X635786Y265027D01*
Y261294D01*
G01X638653Y269294D02*
Y261294D01*
G01X637720Y266627D02*
X639586D01*
G01X641653Y264894D02*
X643786D01*
X643586Y265827D01*
X643253Y266361D01*
X642786Y266627D01*
X642320Y266494D01*
X641920Y266094D01*
X641653Y265161D01*
X641520Y264360D01*
Y263561D01*
X641653Y262761D01*
X641986Y261961D01*
X642386Y261427D01*
X642853Y261294D01*
X643320Y261561D01*
X643786Y262360D01*
G01X645520Y261294D02*
Y269294D01*
G01X647653Y266627D02*
X645520Y263561D01*
G01X646386Y264761D02*
X647786Y261294D01*
G01X654653D02*
X654253Y261427D01*
X653853Y261961D01*
X653586Y262894D01*
X653453Y263961D01*
X653586Y265027D01*
X653853Y265961D01*
X654253Y266494D01*
X654653Y266627D01*
X655053Y266494D01*
X655453Y265961D01*
X655720Y265027D01*
X655786Y263961D01*
X655720Y262894D01*
X655453Y261961D01*
X655053Y261427D01*
X654653Y261294D01*
G01X657720D02*
Y266627D01*
G01Y265561D02*
X658053Y266094D01*
X658386Y266494D01*
X658853Y266627D01*
X659186Y266494D01*
X659586Y266094D01*
G01X665853Y269294D02*
X667453D01*
G01X666653D02*
Y261294D01*
G01X665853D02*
X667453D01*
G01X668653D02*
Y266627D01*
G01Y265161D02*
X668853Y265827D01*
X669186Y266361D01*
X669653Y266627D01*
X670120Y266361D01*
X670453Y265827D01*
X670653Y265161D01*
Y261294D01*
G01Y265161D02*
X670853Y265827D01*
X671186Y266361D01*
X671653Y266627D01*
X672120Y266361D01*
X672453Y265827D01*
X672653Y265027D01*
Y261294D01*
G01X672986D02*
X674653Y269294D01*
X676320Y261294D01*
G01X675720Y264094D02*
X673586D01*
G01X677720Y259294D02*
X678186Y258761D01*
X678720Y258627D01*
X679186Y258761D01*
X679586Y259427D01*
X679853Y260361D01*
Y266627D01*
G01Y265561D02*
X679586Y266094D01*
X679186Y266494D01*
X678720Y266627D01*
X678186Y266361D01*
X677853Y265827D01*
X677586Y264894D01*
X677453Y263961D01*
X677520Y263161D01*
X677786Y262227D01*
X678186Y261561D01*
X678720Y261294D01*
X679120Y261427D01*
X679586Y261961D01*
X679853Y262494D01*
G01X682986Y258627D02*
X683653Y259961D01*
X683986Y261294D01*
Y266627D01*
X683653Y267961D01*
X682986Y269294D01*
G01X483320Y249294D02*
Y257294D01*
X484920D01*
X485453Y256894D01*
X485853Y255961D01*
X485986Y254894D01*
X485853Y253827D01*
X485520Y253027D01*
X484920Y252627D01*
X483320D01*
G01X488653Y257294D02*
Y249294D01*
G01X487120Y257294D02*
X490186D01*
G01X491253Y249294D02*
Y257294D01*
G01X494053D02*
Y249294D01*
G01Y253294D02*
X491253D01*
G01X499520Y249294D02*
Y257294D01*
G01Y253427D02*
X499853Y254094D01*
X500186Y254494D01*
X500720Y254627D01*
X501120Y254494D01*
X501586Y253961D01*
X501786Y253161D01*
Y249294D01*
G01X504653D02*
X504253Y249427D01*
X503853Y249961D01*
X503586Y250894D01*
X503453Y251961D01*
X503586Y253027D01*
X503853Y253961D01*
X504253Y254494D01*
X504653Y254627D01*
X505053Y254494D01*
X505453Y253961D01*
X505720Y253027D01*
X505786Y251961D01*
X505720Y250894D01*
X505453Y249961D01*
X505053Y249427D01*
X504653Y249294D01*
G01X508653D02*
Y257294D01*
G01X511653Y252894D02*
X513786D01*
X513586Y253827D01*
X513253Y254361D01*
X512786Y254627D01*
X512320Y254494D01*
X511920Y254094D01*
X511653Y253161D01*
X511520Y252360D01*
Y251561D01*
X511653Y250761D01*
X511986Y249961D01*
X512386Y249427D01*
X512853Y249294D01*
X513320Y249561D01*
X513786Y250360D01*
G01X520253Y249294D02*
Y256094D01*
X520386Y256761D01*
X520653Y257161D01*
X521053Y257294D01*
X521453Y257027D01*
X521653Y256361D01*
G01X520853Y254094D02*
X519520D01*
G01X524653Y249294D02*
X524253Y249427D01*
X523853Y249961D01*
X523586Y250894D01*
X523453Y251961D01*
X523586Y253027D01*
X523853Y253961D01*
X524253Y254494D01*
X524653Y254627D01*
X525053Y254494D01*
X525453Y253961D01*
X525720Y253027D01*
X525786Y251961D01*
X525720Y250894D01*
X525453Y249961D01*
X525053Y249427D01*
X524653Y249294D01*
G01X527720D02*
Y254627D01*
G01Y253561D02*
X528053Y254094D01*
X528386Y254494D01*
X528853Y254627D01*
X529186Y254494D01*
X529586Y254094D01*
G01X537720Y253961D02*
X537253Y254494D01*
X536853Y254627D01*
X536320Y254361D01*
X535920Y253827D01*
X535653Y252894D01*
X535586Y251961D01*
X535653Y251027D01*
X535920Y250227D01*
X536320Y249561D01*
X536853Y249294D01*
X537320Y249561D01*
X537720Y250094D01*
G01X540653Y249294D02*
X540253Y249427D01*
X539853Y249961D01*
X539586Y250894D01*
X539453Y251961D01*
X539586Y253027D01*
X539853Y253961D01*
X540253Y254494D01*
X540653Y254627D01*
X541053Y254494D01*
X541453Y253961D01*
X541720Y253027D01*
X541786Y251961D01*
X541720Y250894D01*
X541453Y249961D01*
X541053Y249427D01*
X540653Y249294D01*
G01X542653D02*
Y254627D01*
G01Y253161D02*
X542853Y253827D01*
X543186Y254361D01*
X543653Y254627D01*
X544120Y254361D01*
X544453Y253827D01*
X544653Y253161D01*
Y249294D01*
G01Y253161D02*
X544853Y253827D01*
X545186Y254361D01*
X545653Y254627D01*
X546120Y254361D01*
X546453Y253827D01*
X546653Y253027D01*
Y249294D01*
G01X547453Y246627D02*
Y254627D01*
G01Y253427D02*
X547786Y254094D01*
X548120Y254494D01*
X548653Y254627D01*
X549120Y254494D01*
X549586Y253827D01*
X549786Y252894D01*
X549853Y251961D01*
X549786Y251027D01*
X549586Y250094D01*
X549186Y249561D01*
X548653Y249294D01*
X548186Y249427D01*
X547720Y249827D01*
X547453Y250360D01*
G01X552653Y249294D02*
X552253Y249427D01*
X551853Y249961D01*
X551586Y250894D01*
X551453Y251961D01*
X551586Y253027D01*
X551853Y253961D01*
X552253Y254494D01*
X552653Y254627D01*
X553053Y254494D01*
X553453Y253961D01*
X553720Y253027D01*
X553786Y251961D01*
X553720Y250894D01*
X553453Y249961D01*
X553053Y249427D01*
X552653Y249294D01*
G01X555520D02*
Y254627D01*
G01Y253294D02*
X555786Y253961D01*
X556186Y254494D01*
X556720Y254627D01*
X557186Y254494D01*
X557586Y253961D01*
X557786Y253027D01*
Y249294D01*
G01X559653Y252894D02*
X561786D01*
X561586Y253827D01*
X561253Y254361D01*
X560786Y254627D01*
X560320Y254494D01*
X559920Y254094D01*
X559653Y253161D01*
X559520Y252360D01*
Y251561D01*
X559653Y250761D01*
X559986Y249961D01*
X560386Y249427D01*
X560853Y249294D01*
X561320Y249561D01*
X561786Y250360D01*
G01X563520Y249294D02*
Y254627D01*
G01Y253294D02*
X563786Y253961D01*
X564186Y254494D01*
X564720Y254627D01*
X565186Y254494D01*
X565586Y253961D01*
X565786Y253027D01*
Y249294D01*
G01X568653Y257294D02*
Y249294D01*
G01X567720Y254627D02*
X569586D01*
G01X576320Y246627D02*
X575653Y247961D01*
X575320Y249294D01*
Y254627D01*
X575653Y255961D01*
X576320Y257294D01*
G01X580653Y249294D02*
Y257294D01*
X579853Y255694D01*
G01Y249294D02*
X581453D01*
G01X583386Y252627D02*
X583853Y253561D01*
X584253Y254094D01*
X584786Y254361D01*
X585253Y254094D01*
X585586Y253561D01*
X585853Y252761D01*
X585920Y251827D01*
X585853Y251027D01*
X585586Y250227D01*
X585186Y249561D01*
X584720Y249294D01*
X584186Y249561D01*
X583720Y250360D01*
X583453Y251561D01*
X583386Y252894D01*
X583520Y254627D01*
X583720Y255561D01*
X584053Y256494D01*
X584520Y257161D01*
X584986Y257294D01*
X585453Y257027D01*
X585786Y256361D01*
G01X586653Y249294D02*
Y254627D01*
G01Y253161D02*
X586853Y253827D01*
X587186Y254361D01*
X587653Y254627D01*
X588120Y254361D01*
X588453Y253827D01*
X588653Y253161D01*
Y249294D01*
G01Y253161D02*
X588853Y253827D01*
X589186Y254361D01*
X589653Y254627D01*
X590120Y254361D01*
X590453Y253827D01*
X590653Y253027D01*
Y249294D01*
G01X592653Y254627D02*
Y249294D01*
G01Y256761D02*
X592520Y256894D01*
Y257161D01*
X592653Y257294D01*
X592786Y257161D01*
Y256894D01*
X592653Y256761D01*
G01X596653Y249294D02*
Y257294D01*
G01X605986Y249294D02*
X603320Y251961D01*
X605986Y254627D01*
G01X611653Y250227D02*
X611986Y249694D01*
X612453Y249294D01*
X612853D01*
X613253Y249561D01*
X613520Y249961D01*
X613653Y250494D01*
X613586Y251294D01*
X613320Y251694D01*
X612120Y252494D01*
X611853Y253427D01*
X611986Y254094D01*
X612253Y254494D01*
X612653Y254627D01*
X613053Y254494D01*
X613453Y254094D01*
G01X616653Y254627D02*
Y249294D01*
G01Y256761D02*
X616520Y256894D01*
Y257161D01*
X616653Y257294D01*
X616786Y257161D01*
Y256894D01*
X616653Y256761D01*
G01X619653Y254627D02*
X621653D01*
X619653Y249294D01*
X621653D01*
G01X623653Y252894D02*
X625786D01*
X625586Y253827D01*
X625253Y254361D01*
X624786Y254627D01*
X624320Y254494D01*
X623920Y254094D01*
X623653Y253161D01*
X623520Y252360D01*
Y251561D01*
X623653Y250761D01*
X623986Y249961D01*
X624386Y249427D01*
X624853Y249294D01*
X625320Y249561D01*
X625786Y250360D01*
G01X633986Y249294D02*
X631320Y251961D01*
X633986Y254627D01*
G01X636653Y249294D02*
Y257294D01*
X635853Y255694D01*
G01Y249294D02*
X637453D01*
G01X639520Y250227D02*
X639986Y249561D01*
X640520Y249294D01*
X641053Y249561D01*
X641520Y250360D01*
X641853Y251561D01*
X641986Y252761D01*
Y254227D01*
X641853Y255427D01*
X641520Y256494D01*
X641120Y257027D01*
X640653Y257294D01*
X640120Y257027D01*
X639720Y256494D01*
X639453Y255694D01*
X639320Y254627D01*
X639453Y253694D01*
X639786Y252761D01*
X640186Y252227D01*
X640653Y252094D01*
X641186Y252360D01*
X641586Y253027D01*
X641986Y254227D01*
G01X644520Y249294D02*
X644653Y251027D01*
X644853Y252494D01*
X645120Y253827D01*
X645453Y255294D01*
X645986Y257294D01*
X643320D01*
G01X646653Y249294D02*
Y254627D01*
G01Y253161D02*
X646853Y253827D01*
X647186Y254361D01*
X647653Y254627D01*
X648120Y254361D01*
X648453Y253827D01*
X648653Y253161D01*
Y249294D01*
G01Y253161D02*
X648853Y253827D01*
X649186Y254361D01*
X649653Y254627D01*
X650120Y254361D01*
X650453Y253827D01*
X650653Y253027D01*
Y249294D01*
G01X652653Y254627D02*
Y249294D01*
G01Y256761D02*
X652520Y256894D01*
Y257161D01*
X652653Y257294D01*
X652786Y257161D01*
Y256894D01*
X652653Y256761D01*
G01X656653Y249294D02*
Y257294D01*
G01X660986Y246627D02*
X661653Y247961D01*
X661986Y249294D01*
Y254627D01*
X661653Y255961D01*
X660986Y257294D01*
G01X482820Y274294D02*
Y282294D01*
X484420D01*
X484953Y281894D01*
X485353Y280961D01*
X485486Y279894D01*
X485353Y278827D01*
X485020Y278027D01*
X484420Y277627D01*
X482820D01*
G01X488153Y282294D02*
Y274294D01*
G01X486620Y282294D02*
X489686D01*
G01X490753Y274294D02*
Y282294D01*
G01X493553D02*
Y274294D01*
G01Y278294D02*
X490753D01*
G01X499020Y274294D02*
Y282294D01*
G01Y278427D02*
X499353Y279094D01*
X499686Y279494D01*
X500220Y279627D01*
X500620Y279494D01*
X501086Y278961D01*
X501286Y278161D01*
Y274294D01*
G01X504153D02*
X503753Y274427D01*
X503353Y274961D01*
X503086Y275894D01*
X502953Y276961D01*
X503086Y278027D01*
X503353Y278961D01*
X503753Y279494D01*
X504153Y279627D01*
X504553Y279494D01*
X504953Y278961D01*
X505220Y278027D01*
X505286Y276961D01*
X505220Y275894D01*
X504953Y274961D01*
X504553Y274427D01*
X504153Y274294D01*
G01X508153D02*
Y282294D01*
G01X511153Y277894D02*
X513286D01*
X513086Y278827D01*
X512753Y279361D01*
X512286Y279627D01*
X511820Y279494D01*
X511420Y279094D01*
X511153Y278161D01*
X511020Y277360D01*
Y276561D01*
X511153Y275761D01*
X511486Y274961D01*
X511886Y274427D01*
X512353Y274294D01*
X512820Y274561D01*
X513286Y275360D01*
G01X519753Y274294D02*
Y281094D01*
X519886Y281761D01*
X520153Y282161D01*
X520553Y282294D01*
X520953Y282027D01*
X521153Y281361D01*
G01X520353Y279094D02*
X519020D01*
G01X524153Y274294D02*
X523753Y274427D01*
X523353Y274961D01*
X523086Y275894D01*
X522953Y276961D01*
X523086Y278027D01*
X523353Y278961D01*
X523753Y279494D01*
X524153Y279627D01*
X524553Y279494D01*
X524953Y278961D01*
X525220Y278027D01*
X525286Y276961D01*
X525220Y275894D01*
X524953Y274961D01*
X524553Y274427D01*
X524153Y274294D01*
G01X527220D02*
Y279627D01*
G01Y278561D02*
X527553Y279094D01*
X527886Y279494D01*
X528353Y279627D01*
X528686Y279494D01*
X529086Y279094D01*
G01X537220Y278961D02*
X536753Y279494D01*
X536353Y279627D01*
X535820Y279361D01*
X535420Y278827D01*
X535153Y277894D01*
X535086Y276961D01*
X535153Y276027D01*
X535420Y275227D01*
X535820Y274561D01*
X536353Y274294D01*
X536820Y274561D01*
X537220Y275094D01*
G01X540153Y274294D02*
X539753Y274427D01*
X539353Y274961D01*
X539086Y275894D01*
X538953Y276961D01*
X539086Y278027D01*
X539353Y278961D01*
X539753Y279494D01*
X540153Y279627D01*
X540553Y279494D01*
X540953Y278961D01*
X541220Y278027D01*
X541286Y276961D01*
X541220Y275894D01*
X540953Y274961D01*
X540553Y274427D01*
X540153Y274294D01*
G01X542153D02*
Y279627D01*
G01Y278161D02*
X542353Y278827D01*
X542686Y279361D01*
X543153Y279627D01*
X543620Y279361D01*
X543953Y278827D01*
X544153Y278161D01*
Y274294D01*
G01Y278161D02*
X544353Y278827D01*
X544686Y279361D01*
X545153Y279627D01*
X545620Y279361D01*
X545953Y278827D01*
X546153Y278027D01*
Y274294D01*
G01X546953Y271627D02*
Y279627D01*
G01Y278427D02*
X547286Y279094D01*
X547620Y279494D01*
X548153Y279627D01*
X548620Y279494D01*
X549086Y278827D01*
X549286Y277894D01*
X549353Y276961D01*
X549286Y276027D01*
X549086Y275094D01*
X548686Y274561D01*
X548153Y274294D01*
X547686Y274427D01*
X547220Y274827D01*
X546953Y275360D01*
G01X552153Y274294D02*
X551753Y274427D01*
X551353Y274961D01*
X551086Y275894D01*
X550953Y276961D01*
X551086Y278027D01*
X551353Y278961D01*
X551753Y279494D01*
X552153Y279627D01*
X552553Y279494D01*
X552953Y278961D01*
X553220Y278027D01*
X553286Y276961D01*
X553220Y275894D01*
X552953Y274961D01*
X552553Y274427D01*
X552153Y274294D01*
G01X555020D02*
Y279627D01*
G01Y278294D02*
X555286Y278961D01*
X555686Y279494D01*
X556220Y279627D01*
X556686Y279494D01*
X557086Y278961D01*
X557286Y278027D01*
Y274294D01*
G01X559153Y277894D02*
X561286D01*
X561086Y278827D01*
X560753Y279361D01*
X560286Y279627D01*
X559820Y279494D01*
X559420Y279094D01*
X559153Y278161D01*
X559020Y277360D01*
Y276561D01*
X559153Y275761D01*
X559486Y274961D01*
X559886Y274427D01*
X560353Y274294D01*
X560820Y274561D01*
X561286Y275360D01*
G01X563020Y274294D02*
Y279627D01*
G01Y278294D02*
X563286Y278961D01*
X563686Y279494D01*
X564220Y279627D01*
X564686Y279494D01*
X565086Y278961D01*
X565286Y278027D01*
Y274294D01*
G01X568153Y282294D02*
Y274294D01*
G01X567220Y279627D02*
X569086D01*
G01X575820Y271627D02*
X575153Y272961D01*
X574820Y274294D01*
Y279627D01*
X575153Y280961D01*
X575820Y282294D01*
G01X580153Y274294D02*
Y282294D01*
X579353Y280694D01*
G01Y274294D02*
X580953D01*
G01X582886Y277627D02*
X583353Y278561D01*
X583753Y279094D01*
X584286Y279361D01*
X584753Y279094D01*
X585086Y278561D01*
X585353Y277761D01*
X585420Y276827D01*
X585353Y276027D01*
X585086Y275227D01*
X584686Y274561D01*
X584220Y274294D01*
X583686Y274561D01*
X583220Y275360D01*
X582953Y276561D01*
X582886Y277894D01*
X583020Y279627D01*
X583220Y280561D01*
X583553Y281494D01*
X584020Y282161D01*
X584486Y282294D01*
X584953Y282027D01*
X585286Y281361D01*
G01X586153Y274294D02*
Y279627D01*
G01Y278161D02*
X586353Y278827D01*
X586686Y279361D01*
X587153Y279627D01*
X587620Y279361D01*
X587953Y278827D01*
X588153Y278161D01*
Y274294D01*
G01Y278161D02*
X588353Y278827D01*
X588686Y279361D01*
X589153Y279627D01*
X589620Y279361D01*
X589953Y278827D01*
X590153Y278027D01*
Y274294D01*
G01X592153Y279627D02*
Y274294D01*
G01Y281761D02*
X592020Y281894D01*
Y282161D01*
X592153Y282294D01*
X592286Y282161D01*
Y281894D01*
X592153Y281761D01*
G01X596153Y274294D02*
Y282294D01*
G01X605486Y274294D02*
X602820Y276961D01*
X605486Y279627D01*
G01X611153Y275227D02*
X611486Y274694D01*
X611953Y274294D01*
X612353D01*
X612753Y274561D01*
X613020Y274961D01*
X613153Y275494D01*
X613086Y276294D01*
X612820Y276694D01*
X611620Y277494D01*
X611353Y278427D01*
X611486Y279094D01*
X611753Y279494D01*
X612153Y279627D01*
X612553Y279494D01*
X612953Y279094D01*
G01X616153Y279627D02*
Y274294D01*
G01Y281761D02*
X616020Y281894D01*
Y282161D01*
X616153Y282294D01*
X616286Y282161D01*
Y281894D01*
X616153Y281761D01*
G01X619153Y279627D02*
X621153D01*
X619153Y274294D01*
X621153D01*
G01X623153Y277894D02*
X625286D01*
X625086Y278827D01*
X624753Y279361D01*
X624286Y279627D01*
X623820Y279494D01*
X623420Y279094D01*
X623153Y278161D01*
X623020Y277360D01*
Y276561D01*
X623153Y275761D01*
X623486Y274961D01*
X623886Y274427D01*
X624353Y274294D01*
X624820Y274561D01*
X625286Y275360D01*
G01X633486Y274294D02*
X630820Y276961D01*
X633486Y279627D01*
G01X636153Y274294D02*
Y282294D01*
X635353Y280694D01*
G01Y274294D02*
X636953D01*
G01X639020Y275227D02*
X639486Y274561D01*
X640020Y274294D01*
X640553Y274561D01*
X641020Y275360D01*
X641353Y276561D01*
X641486Y277761D01*
Y279227D01*
X641353Y280427D01*
X641020Y281494D01*
X640620Y282027D01*
X640153Y282294D01*
X639620Y282027D01*
X639220Y281494D01*
X638953Y280694D01*
X638820Y279627D01*
X638953Y278694D01*
X639286Y277761D01*
X639686Y277227D01*
X640153Y277094D01*
X640686Y277360D01*
X641086Y278027D01*
X641486Y279227D01*
G01X644020Y274294D02*
X644153Y276027D01*
X644353Y277494D01*
X644620Y278827D01*
X644953Y280294D01*
X645486Y282294D01*
X642820D01*
G01X646153Y274294D02*
Y279627D01*
G01Y278161D02*
X646353Y278827D01*
X646686Y279361D01*
X647153Y279627D01*
X647620Y279361D01*
X647953Y278827D01*
X648153Y278161D01*
Y274294D01*
G01Y278161D02*
X648353Y278827D01*
X648686Y279361D01*
X649153Y279627D01*
X649620Y279361D01*
X649953Y278827D01*
X650153Y278027D01*
Y274294D01*
G01X652153Y279627D02*
Y274294D01*
G01Y281761D02*
X652020Y281894D01*
Y282161D01*
X652153Y282294D01*
X652286Y282161D01*
Y281894D01*
X652153Y281761D01*
G01X656153Y274294D02*
Y282294D01*
G01X660486Y271627D02*
X661153Y272961D01*
X661486Y274294D01*
Y279627D01*
X661153Y280961D01*
X660486Y282294D01*
G01X482320Y294794D02*
Y286794D01*
X484986D01*
G01X488853D02*
Y292127D01*
G01Y291194D02*
X488586Y291727D01*
X488186Y291994D01*
X487720Y292127D01*
X487253Y291861D01*
X486853Y291327D01*
X486586Y290527D01*
X486453Y289461D01*
X486586Y288394D01*
X486853Y287594D01*
X487253Y287061D01*
X487720Y286794D01*
X488186Y286927D01*
X488586Y287327D01*
X488853Y287860D01*
G01X490653Y287727D02*
X490986Y287194D01*
X491453Y286794D01*
X491853D01*
X492253Y287061D01*
X492520Y287461D01*
X492653Y287994D01*
X492586Y288794D01*
X492320Y289194D01*
X491120Y289994D01*
X490853Y290927D01*
X490986Y291594D01*
X491253Y291994D01*
X491653Y292127D01*
X492053Y291994D01*
X492453Y291594D01*
G01X494653Y290394D02*
X496786D01*
X496586Y291327D01*
X496253Y291861D01*
X495786Y292127D01*
X495320Y291994D01*
X494920Y291594D01*
X494653Y290661D01*
X494520Y289860D01*
Y289061D01*
X494653Y288261D01*
X494986Y287461D01*
X495386Y286927D01*
X495853Y286794D01*
X496320Y287061D01*
X496786Y287860D01*
G01X498720Y286794D02*
Y292127D01*
G01Y291061D02*
X499053Y291594D01*
X499386Y291994D01*
X499853Y292127D01*
X500186Y291994D01*
X500586Y291594D01*
G01X506453Y292127D02*
X507653Y286794D01*
X508853Y292127D01*
G01X511653D02*
Y286794D01*
G01Y294261D02*
X511520Y294394D01*
Y294661D01*
X511653Y294794D01*
X511786Y294661D01*
Y294394D01*
X511653Y294261D01*
G01X516853Y286794D02*
Y292127D01*
G01Y291194D02*
X516586Y291727D01*
X516186Y291994D01*
X515720Y292127D01*
X515253Y291861D01*
X514853Y291327D01*
X514586Y290527D01*
X514453Y289461D01*
X514586Y288394D01*
X514853Y287594D01*
X515253Y287061D01*
X515720Y286794D01*
X516186Y286927D01*
X516586Y287327D01*
X516853Y287860D01*
G01X522520Y286794D02*
Y294794D01*
G01Y290927D02*
X522853Y291594D01*
X523186Y291994D01*
X523720Y292127D01*
X524120Y291994D01*
X524586Y291461D01*
X524786Y290661D01*
Y286794D01*
G01X527653D02*
X527253Y286927D01*
X526853Y287461D01*
X526586Y288394D01*
X526453Y289461D01*
X526586Y290527D01*
X526853Y291461D01*
X527253Y291994D01*
X527653Y292127D01*
X528053Y291994D01*
X528453Y291461D01*
X528720Y290527D01*
X528786Y289461D01*
X528720Y288394D01*
X528453Y287461D01*
X528053Y286927D01*
X527653Y286794D01*
G01X531653D02*
Y294794D01*
G01X534653Y290394D02*
X536786D01*
X536586Y291327D01*
X536253Y291861D01*
X535786Y292127D01*
X535320Y291994D01*
X534920Y291594D01*
X534653Y290661D01*
X534520Y289860D01*
Y289061D01*
X534653Y288261D01*
X534986Y287461D01*
X535386Y286927D01*
X535853Y286794D01*
X536320Y287061D01*
X536786Y287860D01*
G01X543320Y284127D02*
X542653Y285461D01*
X542320Y286794D01*
Y292127D01*
X542653Y293461D01*
X543320Y294794D01*
G01X546453Y286794D02*
Y294794D01*
G01Y290794D02*
X546786Y291594D01*
X547186Y291994D01*
X547586Y292127D01*
X548186Y291861D01*
X548586Y291327D01*
X548853Y290394D01*
Y289327D01*
X548720Y288261D01*
X548453Y287461D01*
X547986Y286927D01*
X547586Y286794D01*
X547186Y286927D01*
X546786Y287327D01*
X546453Y287994D01*
G01X550653Y290394D02*
X552786D01*
X552586Y291327D01*
X552253Y291861D01*
X551786Y292127D01*
X551320Y291994D01*
X550920Y291594D01*
X550653Y290661D01*
X550520Y289860D01*
Y289061D01*
X550653Y288261D01*
X550986Y287461D01*
X551386Y286927D01*
X551853Y286794D01*
X552320Y287061D01*
X552786Y287860D01*
G01X555253Y286794D02*
Y293594D01*
X555386Y294261D01*
X555653Y294661D01*
X556053Y294794D01*
X556453Y294527D01*
X556653Y293861D01*
G01X555853Y291594D02*
X554520D01*
G01X559653Y286794D02*
X559253Y286927D01*
X558853Y287461D01*
X558586Y288394D01*
X558453Y289461D01*
X558586Y290527D01*
X558853Y291461D01*
X559253Y291994D01*
X559653Y292127D01*
X560053Y291994D01*
X560453Y291461D01*
X560720Y290527D01*
X560786Y289461D01*
X560720Y288394D01*
X560453Y287461D01*
X560053Y286927D01*
X559653Y286794D01*
G01X562720D02*
Y292127D01*
G01Y291061D02*
X563053Y291594D01*
X563386Y291994D01*
X563853Y292127D01*
X564186Y291994D01*
X564586Y291594D01*
G01X566653Y290394D02*
X568786D01*
X568586Y291327D01*
X568253Y291861D01*
X567786Y292127D01*
X567320Y291994D01*
X566920Y291594D01*
X566653Y290661D01*
X566520Y289860D01*
Y289061D01*
X566653Y288261D01*
X566986Y287461D01*
X567386Y286927D01*
X567853Y286794D01*
X568320Y287061D01*
X568786Y287860D01*
G01X575653Y294794D02*
Y286794D01*
G01X574720Y292127D02*
X576586D01*
G01X578520Y286794D02*
Y294794D01*
G01Y290927D02*
X578853Y291594D01*
X579186Y291994D01*
X579720Y292127D01*
X580120Y291994D01*
X580586Y291461D01*
X580786Y290661D01*
Y286794D01*
G01X582653Y290394D02*
X584786D01*
X584586Y291327D01*
X584253Y291861D01*
X583786Y292127D01*
X583320Y291994D01*
X582920Y291594D01*
X582653Y290661D01*
X582520Y289860D01*
Y289061D01*
X582653Y288261D01*
X582986Y287461D01*
X583386Y286927D01*
X583853Y286794D01*
X584320Y287061D01*
X584786Y287860D01*
G01X592720Y291461D02*
X592253Y291994D01*
X591853Y292127D01*
X591320Y291861D01*
X590920Y291327D01*
X590653Y290394D01*
X590586Y289461D01*
X590653Y288527D01*
X590920Y287727D01*
X591320Y287061D01*
X591853Y286794D01*
X592320Y287061D01*
X592720Y287594D01*
G01X595653Y286794D02*
X595253Y286927D01*
X594853Y287461D01*
X594586Y288394D01*
X594453Y289461D01*
X594586Y290527D01*
X594853Y291461D01*
X595253Y291994D01*
X595653Y292127D01*
X596053Y291994D01*
X596453Y291461D01*
X596720Y290527D01*
X596786Y289461D01*
X596720Y288394D01*
X596453Y287461D01*
X596053Y286927D01*
X595653Y286794D01*
G01X598453Y284127D02*
Y292127D01*
G01Y290927D02*
X598786Y291594D01*
X599120Y291994D01*
X599653Y292127D01*
X600120Y291994D01*
X600586Y291327D01*
X600786Y290394D01*
X600853Y289461D01*
X600786Y288527D01*
X600586Y287594D01*
X600186Y287061D01*
X599653Y286794D01*
X599186Y286927D01*
X598720Y287327D01*
X598453Y287860D01*
G01X602453Y284127D02*
Y292127D01*
G01Y290927D02*
X602786Y291594D01*
X603120Y291994D01*
X603653Y292127D01*
X604120Y291994D01*
X604586Y291327D01*
X604786Y290394D01*
X604853Y289461D01*
X604786Y288527D01*
X604586Y287594D01*
X604186Y287061D01*
X603653Y286794D01*
X603186Y286927D01*
X602720Y287327D01*
X602453Y287860D01*
G01X606653Y290394D02*
X608786D01*
X608586Y291327D01*
X608253Y291861D01*
X607786Y292127D01*
X607320Y291994D01*
X606920Y291594D01*
X606653Y290661D01*
X606520Y289860D01*
Y289061D01*
X606653Y288261D01*
X606986Y287461D01*
X607386Y286927D01*
X607853Y286794D01*
X608320Y287061D01*
X608786Y287860D01*
G01X610720Y286794D02*
Y292127D01*
G01Y291061D02*
X611053Y291594D01*
X611386Y291994D01*
X611853Y292127D01*
X612186Y291994D01*
X612586Y291594D01*
G01X618453Y284127D02*
Y292127D01*
G01Y290927D02*
X618786Y291594D01*
X619120Y291994D01*
X619653Y292127D01*
X620120Y291994D01*
X620586Y291327D01*
X620786Y290394D01*
X620853Y289461D01*
X620786Y288527D01*
X620586Y287594D01*
X620186Y287061D01*
X619653Y286794D01*
X619186Y286927D01*
X618720Y287327D01*
X618453Y287860D01*
G01X623653Y286794D02*
Y294794D01*
G01X628853Y286794D02*
Y292127D01*
G01Y291194D02*
X628586Y291727D01*
X628186Y291994D01*
X627720Y292127D01*
X627253Y291861D01*
X626853Y291327D01*
X626586Y290527D01*
X626453Y289461D01*
X626586Y288394D01*
X626853Y287594D01*
X627253Y287061D01*
X627720Y286794D01*
X628186Y286927D01*
X628586Y287327D01*
X628853Y287860D01*
G01X631653Y294794D02*
Y286794D01*
G01X630720Y292127D02*
X632586D01*
G01X635653D02*
Y286794D01*
G01Y294261D02*
X635520Y294394D01*
Y294661D01*
X635653Y294794D01*
X635786Y294661D01*
Y294394D01*
X635653Y294261D01*
G01X638520Y286794D02*
Y292127D01*
G01Y290794D02*
X638786Y291461D01*
X639186Y291994D01*
X639720Y292127D01*
X640186Y291994D01*
X640586Y291461D01*
X640786Y290527D01*
Y286794D01*
G01X642720Y284794D02*
X643186Y284261D01*
X643720Y284127D01*
X644186Y284261D01*
X644586Y284927D01*
X644853Y285861D01*
Y292127D01*
G01Y291061D02*
X644586Y291594D01*
X644186Y291994D01*
X643720Y292127D01*
X643186Y291861D01*
X642853Y291327D01*
X642586Y290394D01*
X642453Y289461D01*
X642520Y288661D01*
X642786Y287727D01*
X643186Y287061D01*
X643720Y286794D01*
X644120Y286927D01*
X644586Y287461D01*
X644853Y287994D01*
G01X647986Y284127D02*
X648653Y285461D01*
X648986Y286794D01*
Y292127D01*
X648653Y293461D01*
X647986Y294794D01*
G01X481986Y307294D02*
X483653Y299294D01*
X485320Y307294D01*
G01X487653Y304627D02*
Y299294D01*
G01Y306761D02*
X487520Y306894D01*
Y307161D01*
X487653Y307294D01*
X487786Y307161D01*
Y306894D01*
X487653Y306761D01*
G01X492853Y299294D02*
Y304627D01*
G01Y303694D02*
X492586Y304227D01*
X492186Y304494D01*
X491720Y304627D01*
X491253Y304361D01*
X490853Y303827D01*
X490586Y303027D01*
X490453Y301961D01*
X490586Y300894D01*
X490853Y300094D01*
X491253Y299561D01*
X491720Y299294D01*
X492186Y299427D01*
X492586Y299827D01*
X492853Y300360D01*
G01X498253Y299294D02*
Y307294D01*
G01X501053D02*
Y299294D01*
G01Y303294D02*
X498253D01*
G01X503653Y299294D02*
X503253Y299427D01*
X502853Y299961D01*
X502586Y300894D01*
X502453Y301961D01*
X502586Y303027D01*
X502853Y303961D01*
X503253Y304494D01*
X503653Y304627D01*
X504053Y304494D01*
X504453Y303961D01*
X504720Y303027D01*
X504786Y301961D01*
X504720Y300894D01*
X504453Y299961D01*
X504053Y299427D01*
X503653Y299294D01*
G01X507653D02*
Y307294D01*
G01X510653Y302894D02*
X512786D01*
X512586Y303827D01*
X512253Y304361D01*
X511786Y304627D01*
X511320Y304494D01*
X510920Y304094D01*
X510653Y303161D01*
X510520Y302360D01*
Y301561D01*
X510653Y300761D01*
X510986Y299961D01*
X511386Y299427D01*
X511853Y299294D01*
X512320Y299561D01*
X512786Y300360D01*
G01X519320Y296627D02*
X518653Y297961D01*
X518320Y299294D01*
Y304627D01*
X518653Y305961D01*
X519320Y307294D01*
G01X522520Y299294D02*
Y307294D01*
G01Y303427D02*
X522853Y304094D01*
X523186Y304494D01*
X523720Y304627D01*
X524120Y304494D01*
X524586Y303961D01*
X524786Y303161D01*
Y299294D01*
G01X527653D02*
X527253Y299427D01*
X526853Y299961D01*
X526586Y300894D01*
X526453Y301961D01*
X526586Y303027D01*
X526853Y303961D01*
X527253Y304494D01*
X527653Y304627D01*
X528053Y304494D01*
X528453Y303961D01*
X528720Y303027D01*
X528786Y301961D01*
X528720Y300894D01*
X528453Y299961D01*
X528053Y299427D01*
X527653Y299294D01*
G01X531653D02*
Y307294D01*
G01X534653Y302894D02*
X536786D01*
X536586Y303827D01*
X536253Y304361D01*
X535786Y304627D01*
X535320Y304494D01*
X534920Y304094D01*
X534653Y303161D01*
X534520Y302360D01*
Y301561D01*
X534653Y300761D01*
X534986Y299961D01*
X535386Y299427D01*
X535853Y299294D01*
X536320Y299561D01*
X536786Y300360D01*
G01X542653Y300227D02*
X542986Y299694D01*
X543453Y299294D01*
X543853D01*
X544253Y299561D01*
X544520Y299961D01*
X544653Y300494D01*
X544586Y301294D01*
X544320Y301694D01*
X543120Y302494D01*
X542853Y303427D01*
X542986Y304094D01*
X543253Y304494D01*
X543653Y304627D01*
X544053Y304494D01*
X544453Y304094D01*
G01X547653Y304627D02*
Y299294D01*
G01Y306761D02*
X547520Y306894D01*
Y307161D01*
X547653Y307294D01*
X547786Y307161D01*
Y306894D01*
X547653Y306761D01*
G01X550653Y304627D02*
X552653D01*
X550653Y299294D01*
X552653D01*
G01X554653Y302894D02*
X556786D01*
X556586Y303827D01*
X556253Y304361D01*
X555786Y304627D01*
X555320Y304494D01*
X554920Y304094D01*
X554653Y303161D01*
X554520Y302360D01*
Y301561D01*
X554653Y300761D01*
X554986Y299961D01*
X555386Y299427D01*
X555853Y299294D01*
X556320Y299561D01*
X556786Y300360D01*
G01X564986Y299294D02*
X562320Y301961D01*
X564986Y304627D01*
G01X566786Y300761D02*
X568520D01*
G01Y303161D02*
X566786D01*
G01X571653Y299294D02*
Y307294D01*
X570853Y305694D01*
G01Y299294D02*
X572453D01*
G01X574386Y302627D02*
X574853Y303561D01*
X575253Y304094D01*
X575786Y304361D01*
X576253Y304094D01*
X576586Y303561D01*
X576853Y302761D01*
X576920Y301827D01*
X576853Y301027D01*
X576586Y300227D01*
X576186Y299561D01*
X575720Y299294D01*
X575186Y299561D01*
X574720Y300360D01*
X574453Y301561D01*
X574386Y302894D01*
X574520Y304627D01*
X574720Y305561D01*
X575053Y306494D01*
X575520Y307161D01*
X575986Y307294D01*
X576453Y307027D01*
X576786Y306361D01*
G01X581653Y299294D02*
Y304627D01*
G01Y303161D02*
X581853Y303827D01*
X582186Y304361D01*
X582653Y304627D01*
X583120Y304361D01*
X583453Y303827D01*
X583653Y303161D01*
Y299294D01*
G01Y303161D02*
X583853Y303827D01*
X584186Y304361D01*
X584653Y304627D01*
X585120Y304361D01*
X585453Y303827D01*
X585653Y303027D01*
Y299294D01*
G01X587653Y304627D02*
Y299294D01*
G01Y306761D02*
X587520Y306894D01*
Y307161D01*
X587653Y307294D01*
X587786Y307161D01*
Y306894D01*
X587653Y306761D01*
G01X591653Y299294D02*
Y307294D01*
G01X595986Y296627D02*
X596653Y297961D01*
X596986Y299294D01*
Y304627D01*
X596653Y305961D01*
X595986Y307294D01*
G01X496153Y319794D02*
Y311794D01*
G01X495220Y317127D02*
X497086D01*
G01X499020Y311794D02*
Y319794D01*
G01Y315927D02*
X499353Y316594D01*
X499686Y316994D01*
X500220Y317127D01*
X500620Y316994D01*
X501086Y316461D01*
X501286Y315661D01*
Y311794D01*
G01X503153Y315394D02*
X505286D01*
X505086Y316327D01*
X504753Y316861D01*
X504286Y317127D01*
X503820Y316994D01*
X503420Y316594D01*
X503153Y315661D01*
X503020Y314860D01*
Y314061D01*
X503153Y313261D01*
X503486Y312461D01*
X503886Y311927D01*
X504353Y311794D01*
X504820Y312061D01*
X505286Y312860D01*
G01X511220Y311794D02*
Y317127D01*
G01Y316061D02*
X511553Y316594D01*
X511886Y316994D01*
X512353Y317127D01*
X512686Y316994D01*
X513086Y316594D01*
G01X515153Y315394D02*
X517286D01*
X517086Y316327D01*
X516753Y316861D01*
X516286Y317127D01*
X515820Y316994D01*
X515420Y316594D01*
X515153Y315661D01*
X515020Y314860D01*
Y314061D01*
X515153Y313261D01*
X515486Y312461D01*
X515886Y311927D01*
X516353Y311794D01*
X516820Y312061D01*
X517286Y312860D01*
G01X520153Y311794D02*
Y319794D01*
G01X525353Y311794D02*
Y317127D01*
G01Y316194D02*
X525086Y316727D01*
X524686Y316994D01*
X524220Y317127D01*
X523753Y316861D01*
X523353Y316327D01*
X523086Y315527D01*
X522953Y314461D01*
X523086Y313394D01*
X523353Y312594D01*
X523753Y312061D01*
X524220Y311794D01*
X524686Y311927D01*
X525086Y312327D01*
X525353Y312860D01*
G01X528153Y319794D02*
Y311794D01*
G01X527220Y317127D02*
X529086D01*
G01X532153D02*
Y311794D01*
G01Y319261D02*
X532020Y319394D01*
Y319661D01*
X532153Y319794D01*
X532286Y319661D01*
Y319394D01*
X532153Y319261D01*
G01X534953Y317127D02*
X536153Y311794D01*
X537353Y317127D01*
G01X539153Y315394D02*
X541286D01*
X541086Y316327D01*
X540753Y316861D01*
X540286Y317127D01*
X539820Y316994D01*
X539420Y316594D01*
X539153Y315661D01*
X539020Y314860D01*
Y314061D01*
X539153Y313261D01*
X539486Y312461D01*
X539886Y311927D01*
X540353Y311794D01*
X540820Y312061D01*
X541286Y312860D01*
G01X548153Y311794D02*
Y319794D01*
G01X552153Y311794D02*
X551753Y311927D01*
X551353Y312461D01*
X551086Y313394D01*
X550953Y314461D01*
X551086Y315527D01*
X551353Y316461D01*
X551753Y316994D01*
X552153Y317127D01*
X552553Y316994D01*
X552953Y316461D01*
X553220Y315527D01*
X553286Y314461D01*
X553220Y313394D01*
X552953Y312461D01*
X552553Y311927D01*
X552153Y311794D01*
G01X557220Y316461D02*
X556753Y316994D01*
X556353Y317127D01*
X555820Y316861D01*
X555420Y316327D01*
X555153Y315394D01*
X555086Y314461D01*
X555153Y313527D01*
X555420Y312727D01*
X555820Y312061D01*
X556353Y311794D01*
X556820Y312061D01*
X557220Y312594D01*
G01X561353Y311794D02*
Y317127D01*
G01Y316194D02*
X561086Y316727D01*
X560686Y316994D01*
X560220Y317127D01*
X559753Y316861D01*
X559353Y316327D01*
X559086Y315527D01*
X558953Y314461D01*
X559086Y313394D01*
X559353Y312594D01*
X559753Y312061D01*
X560220Y311794D01*
X560686Y311927D01*
X561086Y312327D01*
X561353Y312860D01*
G01X564153Y319794D02*
Y311794D01*
G01X563220Y317127D02*
X565086D01*
G01X568153D02*
Y311794D01*
G01Y319261D02*
X568020Y319394D01*
Y319661D01*
X568153Y319794D01*
X568286Y319661D01*
Y319394D01*
X568153Y319261D01*
G01X572153Y311794D02*
X571753Y311927D01*
X571353Y312461D01*
X571086Y313394D01*
X570953Y314461D01*
X571086Y315527D01*
X571353Y316461D01*
X571753Y316994D01*
X572153Y317127D01*
X572553Y316994D01*
X572953Y316461D01*
X573220Y315527D01*
X573286Y314461D01*
X573220Y313394D01*
X572953Y312461D01*
X572553Y311927D01*
X572153Y311794D01*
G01X575020D02*
Y317127D01*
G01Y315794D02*
X575286Y316461D01*
X575686Y316994D01*
X576220Y317127D01*
X576686Y316994D01*
X577086Y316461D01*
X577286Y315527D01*
Y311794D01*
G01X584153D02*
X583753Y311927D01*
X583353Y312461D01*
X583086Y313394D01*
X582953Y314461D01*
X583086Y315527D01*
X583353Y316461D01*
X583753Y316994D01*
X584153Y317127D01*
X584553Y316994D01*
X584953Y316461D01*
X585220Y315527D01*
X585286Y314461D01*
X585220Y313394D01*
X584953Y312461D01*
X584553Y311927D01*
X584153Y311794D01*
G01X587753D02*
Y318594D01*
X587886Y319261D01*
X588153Y319661D01*
X588553Y319794D01*
X588953Y319527D01*
X589153Y318861D01*
G01X588353Y316594D02*
X587020D01*
G01X595020Y311794D02*
Y319794D01*
G01Y315927D02*
X595353Y316594D01*
X595686Y316994D01*
X596220Y317127D01*
X596620Y316994D01*
X597086Y316461D01*
X597286Y315661D01*
Y311794D01*
G01X600153D02*
X599753Y311927D01*
X599353Y312461D01*
X599086Y313394D01*
X598953Y314461D01*
X599086Y315527D01*
X599353Y316461D01*
X599753Y316994D01*
X600153Y317127D01*
X600553Y316994D01*
X600953Y316461D01*
X601220Y315527D01*
X601286Y314461D01*
X601220Y313394D01*
X600953Y312461D01*
X600553Y311927D01*
X600153Y311794D01*
G01X604153D02*
Y319794D01*
G01X607153Y315394D02*
X609286D01*
X609086Y316327D01*
X608753Y316861D01*
X608286Y317127D01*
X607820Y316994D01*
X607420Y316594D01*
X607153Y315661D01*
X607020Y314860D01*
Y314061D01*
X607153Y313261D01*
X607486Y312461D01*
X607886Y311927D01*
X608353Y311794D01*
X608820Y312061D01*
X609286Y312860D01*
G01X616153Y319794D02*
Y311794D01*
G01X615220Y317127D02*
X617086D01*
G01X620153Y311794D02*
X619753Y311927D01*
X619353Y312461D01*
X619086Y313394D01*
X618953Y314461D01*
X619086Y315527D01*
X619353Y316461D01*
X619753Y316994D01*
X620153Y317127D01*
X620553Y316994D01*
X620953Y316461D01*
X621220Y315527D01*
X621286Y314461D01*
X621220Y313394D01*
X620953Y312461D01*
X620553Y311927D01*
X620153Y311794D01*
G01X627020D02*
Y319794D01*
G01Y315927D02*
X627353Y316594D01*
X627686Y316994D01*
X628220Y317127D01*
X628620Y316994D01*
X629086Y316461D01*
X629286Y315661D01*
Y311794D01*
G01X632153D02*
X631753Y311927D01*
X631353Y312461D01*
X631086Y313394D01*
X630953Y314461D01*
X631086Y315527D01*
X631353Y316461D01*
X631753Y316994D01*
X632153Y317127D01*
X632553Y316994D01*
X632953Y316461D01*
X633220Y315527D01*
X633286Y314461D01*
X633220Y313394D01*
X632953Y312461D01*
X632553Y311927D01*
X632153Y311794D01*
G01X636153D02*
Y319794D01*
G01X639153Y315394D02*
X641286D01*
X641086Y316327D01*
X640753Y316861D01*
X640286Y317127D01*
X639820Y316994D01*
X639420Y316594D01*
X639153Y315661D01*
X639020Y314860D01*
Y314061D01*
X639153Y313261D01*
X639486Y312461D01*
X639886Y311927D01*
X640353Y311794D01*
X640820Y312061D01*
X641286Y312860D01*
G01X642853Y334294D02*
X644453D01*
G01X643653D02*
Y326294D01*
G01X642853D02*
X644453D01*
G01X647653Y334294D02*
Y326294D01*
G01X646720Y331627D02*
X648586D01*
G01X650653Y329894D02*
X652786D01*
X652586Y330827D01*
X652253Y331361D01*
X651786Y331627D01*
X651320Y331494D01*
X650920Y331094D01*
X650653Y330161D01*
X650520Y329360D01*
Y328561D01*
X650653Y327761D01*
X650986Y326961D01*
X651386Y326427D01*
X651853Y326294D01*
X652320Y326561D01*
X652786Y327360D01*
G01X653653Y326294D02*
Y331627D01*
G01Y330161D02*
X653853Y330827D01*
X654186Y331361D01*
X654653Y331627D01*
X655120Y331361D01*
X655453Y330827D01*
X655653Y330161D01*
Y326294D01*
G01Y330161D02*
X655853Y330827D01*
X656186Y331361D01*
X656653Y331627D01*
X657120Y331361D01*
X657453Y330827D01*
X657653Y330027D01*
Y326294D01*
G01X658653Y327227D02*
X658986Y326694D01*
X659453Y326294D01*
X659853D01*
X660253Y326561D01*
X660520Y326961D01*
X660653Y327494D01*
X660586Y328294D01*
X660320Y328694D01*
X659120Y329494D01*
X658853Y330427D01*
X658986Y331094D01*
X659253Y331494D01*
X659653Y331627D01*
X660053Y331494D01*
X660453Y331094D01*
G01X896653Y161894D02*
Y169894D01*
X895853Y168294D01*
G01Y161894D02*
X897453D01*
G01X900653Y161627D02*
X900520Y161761D01*
Y162027D01*
X900653Y162161D01*
X900786Y162027D01*
Y161761D01*
X900653Y161627D01*
G01X904653Y169894D02*
X904120Y169627D01*
X903720Y168961D01*
X903453Y168161D01*
X903253Y167094D01*
X903186Y165894D01*
X903253Y164694D01*
X903453Y163627D01*
X903720Y162827D01*
X904120Y162161D01*
X904653Y161894D01*
X905186Y162161D01*
X905586Y162827D01*
X905853Y163627D01*
X906053Y164694D01*
X906120Y165894D01*
X906053Y167094D01*
X905853Y168161D01*
X905586Y168961D01*
X905186Y169627D01*
X904653Y169894D01*
G01X906653Y161894D02*
Y167227D01*
G01Y165761D02*
X906853Y166427D01*
X907186Y166961D01*
X907653Y167227D01*
X908120Y166961D01*
X908453Y166427D01*
X908653Y165761D01*
Y161894D01*
G01Y165761D02*
X908853Y166427D01*
X909186Y166961D01*
X909653Y167227D01*
X910120Y166961D01*
X910453Y166427D01*
X910653Y165627D01*
Y161894D01*
G01X912653Y167227D02*
Y161894D01*
G01Y169361D02*
X912520Y169494D01*
Y169761D01*
X912653Y169894D01*
X912786Y169761D01*
Y169494D01*
X912653Y169361D01*
G01X916653Y161894D02*
Y169894D01*
G01X922653Y161894D02*
Y167227D01*
G01Y165761D02*
X922853Y166427D01*
X923186Y166961D01*
X923653Y167227D01*
X924120Y166961D01*
X924453Y166427D01*
X924653Y165761D01*
Y161894D01*
G01Y165761D02*
X924853Y166427D01*
X925186Y166961D01*
X925653Y167227D01*
X926120Y166961D01*
X926453Y166427D01*
X926653Y165627D01*
Y161894D01*
G01X929853D02*
Y167227D01*
G01Y166294D02*
X929586Y166827D01*
X929186Y167094D01*
X928720Y167227D01*
X928253Y166961D01*
X927853Y166427D01*
X927586Y165627D01*
X927453Y164561D01*
X927586Y163494D01*
X927853Y162694D01*
X928253Y162161D01*
X928720Y161894D01*
X929186Y162027D01*
X929586Y162427D01*
X929853Y162960D01*
G01X931653Y167227D02*
X933653Y161894D01*
G01Y167227D02*
X931653Y161894D01*
G01X907920Y176461D02*
X909520D01*
G01X908653Y178194D02*
Y174727D01*
G01X911453Y173527D02*
X913853Y181794D01*
G01X915786Y176461D02*
X917520D01*
G01X919186Y174994D02*
X919586Y174327D01*
X920053Y173927D01*
X920653Y173794D01*
X921253Y174061D01*
X921720Y174594D01*
X922053Y175527D01*
X922120Y176594D01*
X921986Y177661D01*
X921653Y178327D01*
X921186Y178861D01*
X920720Y178994D01*
X920253Y178861D01*
X919653Y178327D01*
X919853Y181794D01*
X921653D01*
G01X922653Y173794D02*
Y179127D01*
G01Y177661D02*
X922853Y178327D01*
X923186Y178861D01*
X923653Y179127D01*
X924120Y178861D01*
X924453Y178327D01*
X924653Y177661D01*
Y173794D01*
G01Y177661D02*
X924853Y178327D01*
X925186Y178861D01*
X925653Y179127D01*
X926120Y178861D01*
X926453Y178327D01*
X926653Y177527D01*
Y173794D01*
G01X928653Y179127D02*
Y173794D01*
G01Y181261D02*
X928520Y181394D01*
Y181661D01*
X928653Y181794D01*
X928786Y181661D01*
Y181394D01*
X928653Y181261D01*
G01X932653Y173794D02*
Y181794D01*
G01X907920Y189461D02*
X909520D01*
G01X908653Y191194D02*
Y187727D01*
G01X911453Y186527D02*
X913853Y194794D01*
G01X915786Y189461D02*
X917520D01*
G01X919186Y187994D02*
X919586Y187327D01*
X920053Y186927D01*
X920653Y186794D01*
X921253Y187061D01*
X921720Y187594D01*
X922053Y188527D01*
X922120Y189594D01*
X921986Y190661D01*
X921653Y191327D01*
X921186Y191861D01*
X920720Y191994D01*
X920253Y191861D01*
X919653Y191327D01*
X919853Y194794D01*
X921653D01*
G01X922653Y186794D02*
Y192127D01*
G01Y190661D02*
X922853Y191327D01*
X923186Y191861D01*
X923653Y192127D01*
X924120Y191861D01*
X924453Y191327D01*
X924653Y190661D01*
Y186794D01*
G01Y190661D02*
X924853Y191327D01*
X925186Y191861D01*
X925653Y192127D01*
X926120Y191861D01*
X926453Y191327D01*
X926653Y190527D01*
Y186794D01*
G01X928653Y192127D02*
Y186794D01*
G01Y194261D02*
X928520Y194394D01*
Y194661D01*
X928653Y194794D01*
X928786Y194661D01*
Y194394D01*
X928653Y194261D01*
G01X932653Y186794D02*
Y194794D01*
G01X907920Y201961D02*
X909520D01*
G01X908653Y203694D02*
Y200227D01*
G01X911453Y199027D02*
X913853Y207294D01*
G01X915786Y201961D02*
X917520D01*
G01X920653Y207294D02*
X920120Y207027D01*
X919720Y206361D01*
X919453Y205561D01*
X919253Y204494D01*
X919186Y203294D01*
X919253Y202094D01*
X919453Y201027D01*
X919720Y200227D01*
X920120Y199561D01*
X920653Y199294D01*
X921186Y199561D01*
X921586Y200227D01*
X921853Y201027D01*
X922053Y202094D01*
X922120Y203294D01*
X922053Y204494D01*
X921853Y205561D01*
X921586Y206361D01*
X921186Y207027D01*
X920653Y207294D01*
G01X924653Y199027D02*
X924520Y199161D01*
Y199427D01*
X924653Y199561D01*
X924786Y199427D01*
Y199161D01*
X924653Y199027D01*
G01X928653Y207294D02*
X928120Y207027D01*
X927720Y206361D01*
X927453Y205561D01*
X927253Y204494D01*
X927186Y203294D01*
X927253Y202094D01*
X927453Y201027D01*
X927720Y200227D01*
X928120Y199561D01*
X928653Y199294D01*
X929186Y199561D01*
X929586Y200227D01*
X929853Y201027D01*
X930053Y202094D01*
X930120Y203294D01*
X930053Y204494D01*
X929853Y205561D01*
X929586Y206361D01*
X929186Y207027D01*
X928653Y207294D01*
G01X931186Y200494D02*
X931586Y199827D01*
X932053Y199427D01*
X932653Y199294D01*
X933253Y199561D01*
X933720Y200094D01*
X934053Y201027D01*
X934120Y202094D01*
X933986Y203161D01*
X933653Y203827D01*
X933186Y204361D01*
X932720Y204494D01*
X932253Y204361D01*
X931653Y203827D01*
X931853Y207294D01*
X933653D01*
G01X934653Y199294D02*
Y204627D01*
G01Y203161D02*
X934853Y203827D01*
X935186Y204361D01*
X935653Y204627D01*
X936120Y204361D01*
X936453Y203827D01*
X936653Y203161D01*
Y199294D01*
G01Y203161D02*
X936853Y203827D01*
X937186Y204361D01*
X937653Y204627D01*
X938120Y204361D01*
X938453Y203827D01*
X938653Y203027D01*
Y199294D01*
G01D02*
Y204627D01*
G01Y203161D02*
X938853Y203827D01*
X939186Y204361D01*
X939653Y204627D01*
X940120Y204361D01*
X940453Y203827D01*
X940653Y203161D01*
Y199294D01*
G01Y203161D02*
X940853Y203827D01*
X941186Y204361D01*
X941653Y204627D01*
X942120Y204361D01*
X942453Y203827D01*
X942653Y203027D01*
Y199294D01*
G01X891420Y214161D02*
X893020D01*
G01X892153Y215894D02*
Y212427D01*
G01X896153Y219494D02*
X895620Y219227D01*
X895220Y218561D01*
X894953Y217761D01*
X894753Y216694D01*
X894686Y215494D01*
X894753Y214294D01*
X894953Y213227D01*
X895220Y212427D01*
X895620Y211761D01*
X896153Y211494D01*
X896686Y211761D01*
X897086Y212427D01*
X897353Y213227D01*
X897553Y214294D01*
X897620Y215494D01*
X897553Y216694D01*
X897353Y217761D01*
X897086Y218561D01*
X896686Y219227D01*
X896153Y219494D01*
G01X900153Y211227D02*
X900020Y211361D01*
Y211627D01*
X900153Y211761D01*
X900286Y211627D01*
Y211361D01*
X900153Y211227D01*
G01X904153Y219494D02*
X903620Y219227D01*
X903220Y218561D01*
X902953Y217761D01*
X902753Y216694D01*
X902686Y215494D01*
X902753Y214294D01*
X902953Y213227D01*
X903220Y212427D01*
X903620Y211761D01*
X904153Y211494D01*
X904686Y211761D01*
X905086Y212427D01*
X905353Y213227D01*
X905553Y214294D01*
X905620Y215494D01*
X905553Y216694D01*
X905353Y217761D01*
X905086Y218561D01*
X904686Y219227D01*
X904153Y219494D01*
G01X908020Y211494D02*
X908153Y213227D01*
X908353Y214694D01*
X908620Y216027D01*
X908953Y217494D01*
X909486Y219494D01*
X906820D01*
G01X910686Y212694D02*
X911086Y212027D01*
X911553Y211627D01*
X912153Y211494D01*
X912753Y211761D01*
X913220Y212294D01*
X913553Y213227D01*
X913620Y214294D01*
X913486Y215361D01*
X913153Y216027D01*
X912686Y216561D01*
X912220Y216694D01*
X911753Y216561D01*
X911153Y216027D01*
X911353Y219494D01*
X913153D01*
G01X914953Y211227D02*
X917353Y219494D01*
G01X919286Y214161D02*
X921020D01*
G01X924153Y219494D02*
X923620Y219227D01*
X923220Y218561D01*
X922953Y217761D01*
X922753Y216694D01*
X922686Y215494D01*
X922753Y214294D01*
X922953Y213227D01*
X923220Y212427D01*
X923620Y211761D01*
X924153Y211494D01*
X924686Y211761D01*
X925086Y212427D01*
X925353Y213227D01*
X925553Y214294D01*
X925620Y215494D01*
X925553Y216694D01*
X925353Y217761D01*
X925086Y218561D01*
X924686Y219227D01*
X924153Y219494D01*
G01X926153Y211494D02*
Y216827D01*
G01Y215361D02*
X926353Y216027D01*
X926686Y216561D01*
X927153Y216827D01*
X927620Y216561D01*
X927953Y216027D01*
X928153Y215361D01*
Y211494D01*
G01Y215361D02*
X928353Y216027D01*
X928686Y216561D01*
X929153Y216827D01*
X929620Y216561D01*
X929953Y216027D01*
X930153Y215227D01*
Y211494D01*
G01D02*
Y216827D01*
G01Y215361D02*
X930353Y216027D01*
X930686Y216561D01*
X931153Y216827D01*
X931620Y216561D01*
X931953Y216027D01*
X932153Y215361D01*
Y211494D01*
G01Y215361D02*
X932353Y216027D01*
X932686Y216561D01*
X933153Y216827D01*
X933620Y216561D01*
X933953Y216027D01*
X934153Y215227D01*
Y211494D01*
G01X907920Y226461D02*
X909520D01*
G01X908653Y228194D02*
Y224727D01*
G01X911453Y223527D02*
X913853Y231794D01*
G01X915786Y226461D02*
X917520D01*
G01X919386Y230461D02*
X919786Y231261D01*
X920253Y231661D01*
X920786Y231794D01*
X921453Y231527D01*
X921920Y230861D01*
X922053Y230061D01*
X921986Y229260D01*
X921720Y228594D01*
X920386Y227261D01*
X919786Y226327D01*
X919386Y224994D01*
X919253Y223794D01*
X922053D01*
G01X922653D02*
Y229127D01*
G01Y227661D02*
X922853Y228327D01*
X923186Y228861D01*
X923653Y229127D01*
X924120Y228861D01*
X924453Y228327D01*
X924653Y227661D01*
Y223794D01*
G01Y227661D02*
X924853Y228327D01*
X925186Y228861D01*
X925653Y229127D01*
X926120Y228861D01*
X926453Y228327D01*
X926653Y227527D01*
Y223794D01*
G01X928653Y229127D02*
Y223794D01*
G01Y231261D02*
X928520Y231394D01*
Y231661D01*
X928653Y231794D01*
X928786Y231661D01*
Y231394D01*
X928653Y231261D01*
G01X932653Y223794D02*
Y231794D01*
G01X907920Y264461D02*
X909520D01*
G01X908653Y266194D02*
Y262727D01*
G01X911453Y261527D02*
X913853Y269794D01*
G01X915786Y264461D02*
X917520D01*
G01X919386Y268461D02*
X919786Y269261D01*
X920253Y269661D01*
X920786Y269794D01*
X921453Y269527D01*
X921920Y268861D01*
X922053Y268061D01*
X921986Y267260D01*
X921720Y266594D01*
X920386Y265261D01*
X919786Y264327D01*
X919386Y262994D01*
X919253Y261794D01*
X922053D01*
G01X922653D02*
Y267127D01*
G01Y265661D02*
X922853Y266327D01*
X923186Y266861D01*
X923653Y267127D01*
X924120Y266861D01*
X924453Y266327D01*
X924653Y265661D01*
Y261794D01*
G01Y265661D02*
X924853Y266327D01*
X925186Y266861D01*
X925653Y267127D01*
X926120Y266861D01*
X926453Y266327D01*
X926653Y265527D01*
Y261794D01*
G01X928653Y267127D02*
Y261794D01*
G01Y269261D02*
X928520Y269394D01*
Y269661D01*
X928653Y269794D01*
X928786Y269661D01*
Y269394D01*
X928653Y269261D01*
G01X932653Y261794D02*
Y269794D01*
G01X907920Y246961D02*
X909520D01*
G01X908653Y248694D02*
Y245227D01*
G01X911453Y244027D02*
X913853Y252294D01*
G01X915786Y246961D02*
X917520D01*
G01X919186Y245894D02*
X919586Y244961D01*
X920120Y244427D01*
X920720Y244294D01*
X921253Y244427D01*
X921786Y245094D01*
X922120Y245894D01*
X922186Y246694D01*
X922053Y247627D01*
X921586Y248294D01*
X921120Y248561D01*
X920520D01*
G01X921120D02*
X921520Y248961D01*
X921853Y249627D01*
X921986Y250427D01*
X921853Y251227D01*
X921520Y251894D01*
X920920Y252294D01*
X920320Y252161D01*
X919720Y251627D01*
G01X922653Y244294D02*
Y249627D01*
G01Y248161D02*
X922853Y248827D01*
X923186Y249361D01*
X923653Y249627D01*
X924120Y249361D01*
X924453Y248827D01*
X924653Y248161D01*
Y244294D01*
G01Y248161D02*
X924853Y248827D01*
X925186Y249361D01*
X925653Y249627D01*
X926120Y249361D01*
X926453Y248827D01*
X926653Y248027D01*
Y244294D01*
G01X928653Y249627D02*
Y244294D01*
G01Y251761D02*
X928520Y251894D01*
Y252161D01*
X928653Y252294D01*
X928786Y252161D01*
Y251894D01*
X928653Y251761D01*
G01X932653Y244294D02*
Y252294D01*
G01X907920Y289961D02*
X909520D01*
G01X908653Y291694D02*
Y288227D01*
G01X912653Y287294D02*
Y295294D01*
X911853Y293694D01*
G01Y287294D02*
X913453D01*
G01X915453Y287027D02*
X917853Y295294D01*
G01X919786Y289961D02*
X921520D01*
G01X923186Y288894D02*
X923586Y287961D01*
X924120Y287427D01*
X924720Y287294D01*
X925253Y287427D01*
X925786Y288094D01*
X926120Y288894D01*
X926186Y289694D01*
X926053Y290627D01*
X925586Y291294D01*
X925120Y291561D01*
X924520D01*
G01X925120D02*
X925520Y291961D01*
X925853Y292627D01*
X925986Y293427D01*
X925853Y294227D01*
X925520Y294894D01*
X924920Y295294D01*
X924320Y295161D01*
X923720Y294627D01*
G01X926653Y287294D02*
Y292627D01*
G01Y291161D02*
X926853Y291827D01*
X927186Y292361D01*
X927653Y292627D01*
X928120Y292361D01*
X928453Y291827D01*
X928653Y291161D01*
Y287294D01*
G01Y291161D02*
X928853Y291827D01*
X929186Y292361D01*
X929653Y292627D01*
X930120Y292361D01*
X930453Y291827D01*
X930653Y291027D01*
Y287294D01*
G01X932653Y292627D02*
Y287294D01*
G01Y294761D02*
X932520Y294894D01*
Y295161D01*
X932653Y295294D01*
X932786Y295161D01*
Y294894D01*
X932653Y294761D01*
G01X936653Y287294D02*
Y295294D01*
G01X907920Y301961D02*
X909520D01*
G01X908653Y303694D02*
Y300227D01*
G01X911386Y305961D02*
X911786Y306761D01*
X912253Y307161D01*
X912786Y307294D01*
X913453Y307027D01*
X913920Y306361D01*
X914053Y305561D01*
X913986Y304760D01*
X913720Y304094D01*
X912386Y302761D01*
X911786Y301827D01*
X911386Y300494D01*
X911253Y299294D01*
X914053D01*
G01X915453Y299027D02*
X917853Y307294D01*
G01X919786Y301961D02*
X921520D01*
G01X925453Y299294D02*
Y307294D01*
X922986Y301561D01*
X926320D01*
G01X926653Y299294D02*
Y304627D01*
G01Y303161D02*
X926853Y303827D01*
X927186Y304361D01*
X927653Y304627D01*
X928120Y304361D01*
X928453Y303827D01*
X928653Y303161D01*
Y299294D01*
G01Y303161D02*
X928853Y303827D01*
X929186Y304361D01*
X929653Y304627D01*
X930120Y304361D01*
X930453Y303827D01*
X930653Y303027D01*
Y299294D01*
G01X932653Y304627D02*
Y299294D01*
G01Y306761D02*
X932520Y306894D01*
Y307161D01*
X932653Y307294D01*
X932786Y307161D01*
Y306894D01*
X932653Y306761D01*
G01X936653Y299294D02*
Y307294D01*
G01X902653Y335294D02*
Y327294D01*
G01X901120Y335294D02*
X904186D01*
G01X906653Y327294D02*
X906253Y327427D01*
X905853Y327961D01*
X905586Y328894D01*
X905453Y329961D01*
X905586Y331027D01*
X905853Y331961D01*
X906253Y332494D01*
X906653Y332627D01*
X907053Y332494D01*
X907453Y331961D01*
X907720Y331027D01*
X907786Y329961D01*
X907720Y328894D01*
X907453Y327961D01*
X907053Y327427D01*
X906653Y327294D01*
G01X910653D02*
Y335294D01*
G01X913653Y330894D02*
X915786D01*
X915586Y331827D01*
X915253Y332361D01*
X914786Y332627D01*
X914320Y332494D01*
X913920Y332094D01*
X913653Y331161D01*
X913520Y330360D01*
Y329561D01*
X913653Y328761D01*
X913986Y327961D01*
X914386Y327427D01*
X914853Y327294D01*
X915320Y327561D01*
X915786Y328360D01*
G01X917720Y327294D02*
Y332627D01*
G01Y331561D02*
X918053Y332094D01*
X918386Y332494D01*
X918853Y332627D01*
X919186Y332494D01*
X919586Y332094D01*
G01X923853Y327294D02*
Y332627D01*
G01Y331694D02*
X923586Y332227D01*
X923186Y332494D01*
X922720Y332627D01*
X922253Y332361D01*
X921853Y331827D01*
X921586Y331027D01*
X921453Y329961D01*
X921586Y328894D01*
X921853Y328094D01*
X922253Y327561D01*
X922720Y327294D01*
X923186Y327427D01*
X923586Y327827D01*
X923853Y328360D01*
G01X925520Y327294D02*
Y332627D01*
G01Y331294D02*
X925786Y331961D01*
X926186Y332494D01*
X926720Y332627D01*
X927186Y332494D01*
X927586Y331961D01*
X927786Y331027D01*
Y327294D01*
G01X931720Y331961D02*
X931253Y332494D01*
X930853Y332627D01*
X930320Y332361D01*
X929920Y331827D01*
X929653Y330894D01*
X929586Y329961D01*
X929653Y329027D01*
X929920Y328227D01*
X930320Y327561D01*
X930853Y327294D01*
X931320Y327561D01*
X931720Y328094D01*
G01X933653Y330894D02*
X935786D01*
X935586Y331827D01*
X935253Y332361D01*
X934786Y332627D01*
X934320Y332494D01*
X933920Y332094D01*
X933653Y331161D01*
X933520Y330360D01*
Y329561D01*
X933653Y328761D01*
X933986Y327961D01*
X934386Y327427D01*
X934853Y327294D01*
X935320Y327561D01*
X935786Y328360D01*
G01X907920Y314461D02*
X909520D01*
G01X908653Y316194D02*
Y312727D01*
G01X911453Y311527D02*
X913853Y319794D01*
G01X915786Y314461D02*
X917520D01*
G01X919186Y313394D02*
X919586Y312461D01*
X920120Y311927D01*
X920720Y311794D01*
X921253Y311927D01*
X921786Y312594D01*
X922120Y313394D01*
X922186Y314194D01*
X922053Y315127D01*
X921586Y315794D01*
X921120Y316061D01*
X920520D01*
G01X921120D02*
X921520Y316461D01*
X921853Y317127D01*
X921986Y317927D01*
X921853Y318727D01*
X921520Y319394D01*
X920920Y319794D01*
X920320Y319661D01*
X919720Y319127D01*
G01X922653Y311794D02*
Y317127D01*
G01Y315661D02*
X922853Y316327D01*
X923186Y316861D01*
X923653Y317127D01*
X924120Y316861D01*
X924453Y316327D01*
X924653Y315661D01*
Y311794D01*
G01Y315661D02*
X924853Y316327D01*
X925186Y316861D01*
X925653Y317127D01*
X926120Y316861D01*
X926453Y316327D01*
X926653Y315527D01*
Y311794D01*
G01X928653Y317127D02*
Y311794D01*
G01Y319261D02*
X928520Y319394D01*
Y319661D01*
X928653Y319794D01*
X928786Y319661D01*
Y319394D01*
X928653Y319261D01*
G01X932653Y311794D02*
Y319794D01*
G01X-329247Y900694D02*
Y31894D01*
X1211653D01*
Y900694D01*
X-329247D01*
G01Y482294D02*
X1211653D01*
G01X-143747Y269094D02*
Y290294D01*
X-143847Y290394D01*
X-148247Y285994D01*
G01X-143547Y290194D02*
Y290094D01*
X-139447Y285994D01*
G01X-142747Y329794D02*
X-142647D01*
X-139547Y332894D01*
G01X-142747Y330194D02*
X-142347D01*
G01X-142647Y350094D02*
Y330294D01*
X-142947Y329994D01*
X-145947Y332994D01*
G01X-105747Y290294D02*
X-165547D01*
X-165647Y290394D01*
G01X-105847Y329794D02*
X-165747D01*
G01X-147174Y735091D02*
X-147164Y723091D01*
G01X-147174Y735091D02*
X-123153Y711111D01*
X-123147Y671794D01*
G01X-147174Y735091D02*
X-135174Y735101D01*
G01X-78647Y204794D02*
X-78847D01*
X-81447Y202194D01*
G01X-78547Y237194D02*
Y189594D01*
G01X-99347Y231694D02*
Y231494D01*
X-96847Y228994D01*
G01X-84047Y231594D02*
X-99247D01*
X-99347Y231694D01*
X-96747Y234294D01*
G01X-105647Y231794D02*
Y231494D01*
X-107547Y229594D01*
G01X-130247Y231594D02*
X-105647D01*
X-105447Y231794D01*
X-107847Y234194D01*
G01X-99447Y274394D02*
Y225394D01*
X-99547Y225294D01*
G01X-105447Y274194D02*
Y224994D01*
X-105547Y224894D01*
G01X-117747Y204794D02*
X-78847D01*
X-78547Y205094D01*
X-81147Y207694D01*
G01X-105147Y403694D02*
Y403594D01*
X-103347Y401794D01*
G01X-91647Y403694D02*
X-105047D01*
X-105247Y403894D01*
X-103147Y405994D01*
G01X-105447Y348894D02*
Y420894D01*
G01X-89727Y716264D02*
X-47727D01*
G01X-89727D02*
X-81727Y708264D01*
G01X-89727Y716264D02*
X-81727Y724264D01*
G01X-101267Y742834D02*
X-77267Y766834D01*
X-45267D01*
G01X-101267Y742834D02*
Y754834D01*
G01Y742834D02*
X-89267D01*
G01X-53447Y205194D02*
Y205094D01*
X-50247Y201894D01*
G01X-53547Y237694D02*
Y189694D01*
G01X-547Y237694D02*
X-347D01*
X3253Y241294D01*
G01X-647Y237594D02*
X-1147D01*
X-5047Y241494D01*
G01X-747Y291494D02*
Y237794D01*
X-1347Y237194D01*
G01X-53547D02*
X40853D01*
X41453Y236594D01*
G01X-22247Y205094D02*
X-53347D01*
X-53547Y205294D01*
X-50547Y208294D01*
G01X-1847Y382794D02*
Y331594D01*
X-1347Y331094D01*
G01X-1847Y383194D02*
X1353Y379994D01*
G01X-1947Y383294D02*
X-5347Y379894D01*
G01X-54547Y383394D02*
X34753D01*
X35253Y383894D01*
G01X-26347Y403994D02*
Y403894D01*
X-28947Y401294D01*
G01X-47347Y403894D02*
X-26447D01*
X-26247Y404094D01*
X-29047Y406894D01*
X-29147D01*
G01X-26347Y345794D02*
Y418294D01*
X-26247Y418394D01*
G01X313953Y900794D02*
Y31894D01*
G01X337653Y159294D02*
X990653D01*
Y339294D01*
X337653D01*
Y159294D01*
G01X990653Y171794D02*
X337653D01*
G01Y196794D02*
Y184294D01*
X365653D01*
Y196794D01*
G01X337653Y209294D02*
Y196794D01*
X365653D01*
Y209294D01*
G01X337653Y221794D02*
Y209294D01*
X365653D01*
Y221794D01*
G01X337653Y234294D02*
Y221794D01*
X365653D01*
Y234294D01*
G01X337653Y246794D02*
Y234294D01*
X365653D01*
Y246794D01*
G01X337653Y271794D02*
Y259294D01*
X365653D01*
Y271794D01*
G01X337653Y296794D02*
Y284294D01*
X365653D01*
Y296794D01*
G01X337653Y309294D02*
Y296794D01*
X365653D01*
Y309294D01*
G01X337653Y321794D02*
Y309294D01*
X365653D01*
Y321794D01*
G01X990653D02*
X337653D01*
G01X346653Y339294D02*
X990653D01*
Y321794D01*
X337653D01*
Y339294D01*
X346653D01*
G01X365653Y159294D02*
Y184294D01*
G01Y159294D02*
X479653D01*
Y322294D01*
G01X365153Y299794D02*
X365653D01*
Y243294D01*
G01Y321794D02*
Y339294D01*
G01Y309294D02*
X479653D01*
Y321794D01*
G01X990653Y184294D02*
X479653D01*
G01X990653Y196794D02*
X479653D01*
G01Y209294D02*
X990653D01*
Y221794D01*
G01D02*
X479653D01*
G01X990653Y234294D02*
X479653D01*
G01X990653Y259294D02*
X479653D01*
G01X990653Y296794D02*
X479653D01*
G01X990653Y284294D02*
X479653D01*
G01Y321794D02*
Y339294D01*
G01X990653Y309294D02*
X479653D01*
G01X889153Y159294D02*
Y339294D01*
G01X899153Y184294D02*
X990653D01*
Y196794D01*
G01X899153D02*
X990653D01*
Y209294D01*
G01X899153Y221794D02*
X990653D01*
Y234294D01*
G01X899153D02*
X990653D01*
Y259294D01*
G01X899153D02*
X990653D01*
Y296794D01*
G01X899153Y284294D02*
X990653D01*
Y296794D01*
G01X899153D02*
X990653D01*
Y309294D01*
G01X899153D02*
X990653D01*
Y321794D01*
G01X971853Y482294D02*
Y482394D01*
M02*
